FILE_TYPE = MACRO_DRAWING;
SET COLOR_WIRE YELLOW;
SET COLOR_PROP ORANGE;
SET COLOR_DOT WHITE;
SET COLOR_ARC YELLOW;
SET COLOR_BODY GREEN;
SET COLOR_NOTE PURPLE;
SET PROP_DISPLAY VALUE;
SET PAGE_NUMBER P153;
FORCEADD UNIVERSAL_GND..1
(5850 8150);
FORCEPROP 3 LASTPIN (5850 8200) SIG_NAME GND\g
J 0
(5860 8210);
DISPLAY 0.659574 (5860 8210);
PAINT MONO (5860 8210);
DISPLAY INVISIBLE (5860 8210);
FORCEPROP 1 LAST HDL_POWER GND
J 1
(5875 8075);
DISPLAY 0.872340 (5875 8075);
PAINT GREEN (5875 8075);
DISPLAY INVISIBLE (5875 8075);
FORCEPROP 2 LAST CDS_LIB logical_power
J 0
(5850 8150);
PAINT MONO (5850 8150);
DISPLAY INVISIBLE (5850 8150);
FORCEPROP 1 LAST PATH I1
J 0
(5925 8150);
DISPLAY 0.872340 (5925 8150);
PAINT AQUA (5925 8150);
DISPLAY INVISIBLE (5925 8150);
FORCEADD GND..1
(3375 9900);
FORCEPROP 3 LASTPIN (3375 9950) SIG_NAME GND\g
J 0
(3385 9960);
DISPLAY 0.659574 (3385 9960);
PAINT MONO (3385 9960);
DISPLAY INVISIBLE (3385 9960);
FORCEPROP 1 LAST HDL_POWER GND
J 0
(3375 10050);
DISPLAY 0.872340 (3375 10050);
PAINT GREEN (3375 10050);
DISPLAY INVISIBLE (3375 10050);
FORCEPROP 2 LAST CDS_LIB logical_power
J 0
(3375 9900);
DISPLAY INVISIBLE (3375 9900);
FORCEPROP 1 LAST SIZE 1B
J 0
(3450 9850);
DISPLAY 0.872340 (3450 9850);
PAINT GREEN (3450 9850);
DISPLAY INVISIBLE (3450 9850);
FORCEPROP 1 LAST PATH I10
J 0
(3450 9900);
DISPLAY 0.872340 (3450 9900);
PAINT AQUA (3450 9900);
DISPLAY INVISIBLE (3450 9900);
FORCEADD OFFPAGE..2
(10525 10375);
PAINT AQUA (10525 10375);
FORCEPROP 2 LAST $XR0 250 
J 0
(10714 10375);
DISPLAY 0.638298 (10714 10375);
PAINT MONO (10714 10375);
FORCEPROP 1 LAST COMMENT_BODY TRUE
J 0
(10480 10280);
DISPLAY 0.872340 (10480 10280);
PAINT GREEN (10480 10280);
DISPLAY INVISIBLE (10480 10280);
FORCEPROP 1 LAST OFFPAGE TRUE
J 0
(10850 10250);
DISPLAY 0.872340 (10850 10250);
PAINT AQUA (10850 10250);
DISPLAY INVISIBLE (10850 10250);
FORCEPROP 2 LAST CDS_LIB standard
J 0
(10525 10375);
DISPLAY INVISIBLE (10525 10375);
FORCEPROP 2 LAST PATH I100
J 0
(10725 10400);
DISPLAY 1.021277 (10725 10400);
DISPLAY INVISIBLE (10725 10400);
FORCEADD Q_CAP..1
(8575 13125);
FORCEPROP 1 LAST PART_NUMBER CH31006KB18
J 0
(8630 13017);
DISPLAY 0.638298 (8630 13017);
DISPLAY INVISIBLE (8630 13017);
FORCEPROP 1 LAST VALUE 0.01UF
J 0
(8625 13175);
DISPLAY 0.638298 (8625 13175);
FORCEPROP 1 LAST VOLTAGE 50V
J 0
(8630 13117);
DISPLAY 0.638298 (8630 13117);
FORCEPROP 1 LAST PACK_TYPE C0402
J 0
(8630 13067);
DISPLAY 0.638298 (8630 13067);
FORCEPROP 1 LAST MATERIAL EMPTY
J 0
(8625 13025);
DISPLAY 0.638298 (8625 13025);
PAINT RED (8625 13025);
FORCEPROP 1 LAST LOCATION PC2144
J 0
(8625 13225);
DISPLAY 0.638298 (8625 13225);
FORCEPROP 2 LAST CDS_LIB pure_quanta
J 0
(8575 13125);
DISPLAY INVISIBLE (8575 13125);
FORCEPROP 1 LAST TOLERANCE 10%
J 0
(8625 13075);
DISPLAY 0.638298 (8625 13075);
DISPLAY INVISIBLE (8625 13075);
FORCEPROP 1 LAST PATH I101
J 0
(8625 13275);
DISPLAY 0.978723 (8625 13275);
PAINT WHITE (8625 13275);
DISPLAY INVISIBLE (8625 13275);
FORCEPROP 0 LAST $SEC 1
J 0
(8625 13275);
DISPLAY 0.680851 (8625 13275);
PAINT MONO (8625 13275);
DISPLAY INVISIBLE (8625 13275);
FORCEPROP 0 LAST CDS_SEC 1
J 0
(8625 13275);
DISPLAY 1.021277 (8625 13275);
DISPLAY INVISIBLE (8625 13275);
FORCEPROP 1 LASTPIN (8575 13225) $PN 1
J 0
(8585 13205);
DISPLAY 0.787234 (8585 13205);
PAINT MONO (8585 13205);
DISPLAY INVISIBLE (8585 13205);
FORCEPROP 1 LASTPIN (8575 13025) $PN 2
J 0
(8585 13005);
DISPLAY 0.787234 (8585 13005);
PAINT MONO (8585 13005);
DISPLAY INVISIBLE (8585 13005);
FORCEADD Q_RES..2
(8600 12450);
FORCEPROP 1 LAST PART_NUMBER CS24532FB03
J 0
(8640 12325);
DISPLAY 0.404255 (8640 12325);
DISPLAY INVISIBLE (8640 12325);
FORCEPROP 1 LAST PACK_TYPE 0402LF
J 0
(8640 12275);
DISPLAY 0.404255 (8640 12275);
FORCEPROP 1 LAST MATERIAL CHIP
J 0
(8640 12375);
DISPLAY 0.404255 (8640 12375);
FORCEPROP 1 LAST WATTAGE 1/16W
J 0
(8640 12425);
DISPLAY 0.404255 (8640 12425);
FORCEPROP 1 LAST TOLERANCE 1%
J 0
(8645 12475);
DISPLAY 0.404255 (8645 12475);
FORCEPROP 2 LAST ROOM NIC1_P3V3_BOM1
J 0
(8650 12625);
DISPLAY 0.638298 (8650 12625);
FORCEPROP 1 LAST VALUE 4.53K
J 0
(8645 12525);
DISPLAY 0.404255 (8645 12525);
FORCEPROP 1 LAST $LOCATION PR5481
J 0
(8645 12575);
DISPLAY 0.638298 (8645 12575);
FORCEPROP 1 LASTPIN (8600 12550) $PN 1
J 0
(8605 12512);
DISPLAY 0.787234 (8605 12512);
PAINT MONO (8605 12512);
FORCEPROP 1 LASTPIN (8600 12350) $PN 2
J 0
(8605 12360);
DISPLAY 0.787234 (8605 12360);
PAINT MONO (8605 12360);
FORCEPROP 2 LAST CDS_LIB pure_quanta
J 0
(8600 12450);
DISPLAY INVISIBLE (8600 12450);
FORCEPROP 1 LAST PATH I102
J 0
(8650 12625);
DISPLAY 0.978723 (8650 12625);
PAINT WHITE (8650 12625);
DISPLAY INVISIBLE (8650 12625);
FORCEPROP 0 LAST CDS_LOCATION PR5481
J 0
(8650 12625);
DISPLAY 1.021277 (8650 12625);
DISPLAY INVISIBLE (8650 12625);
FORCEPROP 0 LAST $SEC 1
J 0
(8650 12625);
DISPLAY 0.680851 (8650 12625);
PAINT MONO (8650 12625);
DISPLAY INVISIBLE (8650 12625);
FORCEPROP 0 LAST CDS_SEC 1
J 0
(8650 12625);
DISPLAY 1.021277 (8650 12625);
DISPLAY INVISIBLE (8650 12625);
FORCEADD Q_RES..2
(8825 13125);
FORCEPROP 1 LAST PART_NUMBER CS61002FB02
J 0
(8865 13000);
DISPLAY 0.638298 (8865 13000);
DISPLAY INVISIBLE (8865 13000);
FORCEPROP 1 LAST TOLERANCE 1%
J 0
(8870 13150);
DISPLAY 0.638298 (8870 13150);
FORCEPROP 1 LAST MATERIAL CHIP
J 0
(8865 13050);
DISPLAY 0.638298 (8865 13050);
FORCEPROP 2 LAST ROOM NIC1_P3V3_BOM1
J 0
(8875 13300);
DISPLAY 0.638298 (8875 13300);
FORCEPROP 1 LAST WATTAGE 1/16W
J 0
(8865 13100);
DISPLAY 0.638298 (8865 13100);
FORCEPROP 1 LAST PACK_TYPE 0402LF
J 0
(8865 12950);
DISPLAY 0.638298 (8865 12950);
FORCEPROP 1 LAST VALUE 10M
J 0
(8870 13200);
DISPLAY 0.638298 (8870 13200);
FORCEPROP 1 LAST LOCATION PR4525
J 0
(8870 13250);
DISPLAY 0.638298 (8870 13250);
FORCEPROP 1 LASTPIN (8825 13225) $PN 1
J 0
(8830 13187);
DISPLAY 0.787234 (8830 13187);
PAINT MONO (8830 13187);
FORCEPROP 1 LASTPIN (8825 13025) $PN 2
J 0
(8830 13035);
DISPLAY 0.787234 (8830 13035);
PAINT MONO (8830 13035);
FORCEPROP 2 LAST CDS_LIB pure_quanta
J 0
(8825 13125);
DISPLAY INVISIBLE (8825 13125);
FORCEPROP 1 LAST PATH I103
J 0
(8875 13300);
DISPLAY 0.978723 (8875 13300);
PAINT WHITE (8875 13300);
DISPLAY INVISIBLE (8875 13300);
FORCEPROP 0 LAST $SEC 1
J 0
(8875 13300);
DISPLAY 0.680851 (8875 13300);
PAINT MONO (8875 13300);
DISPLAY INVISIBLE (8875 13300);
FORCEPROP 0 LAST CDS_SEC 1
J 0
(8875 13300);
DISPLAY 1.021277 (8875 13300);
DISPLAY INVISIBLE (8875 13300);
FORCEADD SCHOTTKY_AC..1
R 1
(8950 13700);
FORCEPROP 1 LAST PART_NUMBER BC000340Z30
J 0
(9000 13625);
DISPLAY 0.595745 (9000 13625);
PAINT GREEN (9000 13625);
DISPLAY INVISIBLE (9000 13625);
FORCEPROP 1 LAST MATERIAL IC
J 0
(9000 13600);
DISPLAY 0.723404 (9000 13600);
PAINT GREEN (9000 13600);
FORCEPROP 2 LAST VALUE B340A-13-F
J 0
(9000 13675);
DISPLAY 0.638298 (9000 13675);
FORCEPROP 1 LAST LOCATION PD103
J 0
(9000 13725);
DISPLAY 0.723404 (9000 13725);
PAINT GREEN (9000 13725);
FORCEPROP 0 LASTPIN (8950 13575) $PN A
R 1
J 2
(8940 13610);
DISPLAY 0.808511 (8940 13610);
FORCEPROP 0 LASTPIN (8950 13825) $PN C
R 1
J 0
(8940 13785);
DISPLAY 0.808511 (8940 13785);
FORCEPROP 1 LAST CDS_LMAN_SYM_OUTLINE -75,50,75,-50
R 1
J 0
(8950 13700);
DISPLAY 0.468085 (8950 13700);
PAINT GREEN (8950 13700);
DISPLAY INVISIBLE (8950 13700);
FORCEPROP 2 LAST CDS_LIB pure_quanta
R 1
J 0
(8950 13700);
DISPLAY INVISIBLE (8950 13700);
FORCEPROP 0 LAST PART_TYPE SMLF
J 0
(9000 13875);
DISPLAY 1.021277 (9000 13875);
DISPLAY INVISIBLE (9000 13875);
FORCEPROP 1 LAST NEEDS_NO_SIZE TRUE
R 1
J 0
(9000 13775);
DISPLAY 0.468085 (9000 13775);
PAINT GREEN (9000 13775);
DISPLAY INVISIBLE (9000 13775);
FORCEPROP 1 LAST PATH I104
R 1
J 0
(8950 13700);
DISPLAY 0.723404 (8950 13700);
PAINT GREEN (8950 13700);
DISPLAY INVISIBLE (8950 13700);
FORCEPROP 0 LAST $SEC 1
R 1
J 0
(9000 13775);
DISPLAY INVISIBLE (9000 13775);
FORCEPROP 0 LAST CDS_SEC 1
R 1
J 0
(9000 13775);
DISPLAY INVISIBLE (9000 13775);
FORCEADD Q_RES..1
(9225 12800);
FORCEPROP 1 LAST PART_NUMBER CS00002JB13
J 0
(9050 12750);
DISPLAY 0.595745 (9050 12750);
DISPLAY INVISIBLE (9050 12750);
FORCEPROP 1 LAST TOLERANCE 5%
J 0
(9400 12800);
DISPLAY 0.595745 (9400 12800);
FORCEPROP 1 LAST VALUE 0
J 2
(9375 12800);
DISPLAY 0.595745 (9375 12800);
FORCEPROP 1 LAST MATERIAL CHIP
J 0
(9000 12800);
DISPLAY 0.595745 (9000 12800);
FORCEPROP 1 LAST WATTAGE 1/16W
J 2
(9025 12750);
DISPLAY 0.595745 (9025 12750);
FORCEPROP 2 LAST ROOM NIC1_P3V3_BOM1
J 0
(9025 12725);
DISPLAY 0.638298 (9025 12725);
FORCEPROP 1 LAST PACK_TYPE 0402LF
J 0
(9375 12750);
DISPLAY 0.595745 (9375 12750);
FORCEPROP 1 LAST $LOCATION R3794
J 0
(8875 12800);
DISPLAY 0.638298 (8875 12800);
FORCEPROP 2 LAST CDS_LIB pure_quanta
J 0
(9225 12800);
DISPLAY INVISIBLE (9225 12800);
FORCEPROP 1 LAST PATH I105
J 0
(9175 12950);
DISPLAY 0.978723 (9175 12950);
PAINT WHITE (9175 12950);
DISPLAY INVISIBLE (9175 12950);
FORCEPROP 0 LAST CDS_LOCATION R3794
J 0
(9200 12875);
DISPLAY 1.021277 (9200 12875);
DISPLAY INVISIBLE (9200 12875);
FORCEPROP 0 LAST $SEC 1
J 0
(9200 12875);
DISPLAY 0.680851 (9200 12875);
PAINT MONO (9200 12875);
DISPLAY INVISIBLE (9200 12875);
FORCEPROP 0 LAST CDS_SEC 1
J 0
(9200 12875);
DISPLAY 1.021277 (9200 12875);
DISPLAY INVISIBLE (9200 12875);
FORCEPROP 1 LASTPIN (9125 12800) $PN 1
J 0
(9137 12812);
DISPLAY 0.787234 (9137 12812);
PAINT MONO (9137 12812);
DISPLAY INVISIBLE (9137 12812);
FORCEPROP 1 LASTPIN (9325 12800) $PN 2
J 0
(9287 12812);
DISPLAY 0.787234 (9287 12812);
PAINT MONO (9287 12812);
DISPLAY INVISIBLE (9287 12812);
FORCEADD GND..1
(9300 12825);
FORCEPROP 3 LASTPIN (9300 12875) SIG_NAME GND\g
J 0
(9310 12885);
DISPLAY 0.659574 (9310 12885);
PAINT MONO (9310 12885);
DISPLAY INVISIBLE (9310 12885);
FORCEPROP 2 LAST CDS_LIB logical_power
J 0
(9300 12825);
DISPLAY INVISIBLE (9300 12825);
FORCEPROP 1 LAST HDL_POWER GND
J 0
(9300 12975);
DISPLAY 0.872340 (9300 12975);
PAINT GREEN (9300 12975);
DISPLAY INVISIBLE (9300 12975);
FORCEPROP 1 LAST SIZE 1B
J 0
(9375 12775);
DISPLAY 0.872340 (9375 12775);
PAINT GREEN (9375 12775);
DISPLAY INVISIBLE (9375 12775);
FORCEPROP 1 LAST PATH I106
J 0
(9375 12825);
DISPLAY 0.872340 (9375 12825);
PAINT AQUA (9375 12825);
DISPLAY INVISIBLE (9375 12825);
FORCEADD Q_CAP..1
R 1
(9175 12900);
FORCEPROP 1 LAST PART_NUMBER CH2686K1B01
J 0
(9225 12900);
DISPLAY 0.638298 (9225 12900);
DISPLAY INVISIBLE (9225 12900);
FORCEPROP 2 LAST ROOM NIC1_P3V3_BOM1
J 0
(9200 13000);
DISPLAY 0.510638 (9200 13000);
FORCEPROP 1 LAST VOLTAGE 50V
J 0
(9275 12950);
DISPLAY 0.638298 (9275 12950);
FORCEPROP 1 LAST PACK_TYPE C0402
J 0
(8950 12850);
DISPLAY 0.638298 (8950 12850);
FORCEPROP 1 LAST VALUE 6800PF
J 0
(9075 12950);
DISPLAY 0.638298 (9075 12950);
FORCEPROP 1 LAST LOCATION PC2089
J 0
(8950 12900);
DISPLAY 0.638298 (8950 12900);
FORCEPROP 2 LAST CDS_LIB pure_quanta
R 1
J 0
(9175 12900);
DISPLAY INVISIBLE (9175 12900);
FORCEPROP 1 LAST MATERIAL X7R
R 1
J 0
(9175 12950);
DISPLAY 0.638298 (9175 12950);
DISPLAY INVISIBLE (9175 12950);
FORCEPROP 1 LAST TOLERANCE 10%
R 1
J 0
(9225 12950);
DISPLAY 0.638298 (9225 12950);
DISPLAY INVISIBLE (9225 12950);
FORCEPROP 1 LAST PATH I107
R 1
J 0
(9025 12950);
DISPLAY 0.978723 (9025 12950);
PAINT WHITE (9025 12950);
DISPLAY INVISIBLE (9025 12950);
FORCEPROP 0 LAST $SEC 1
R 1
J 0
(9275 13025);
DISPLAY 0.680851 (9275 13025);
PAINT MONO (9275 13025);
DISPLAY INVISIBLE (9275 13025);
FORCEPROP 0 LAST CDS_SEC 1
R 1
J 0
(9275 13025);
DISPLAY 1.021277 (9275 13025);
DISPLAY INVISIBLE (9275 13025);
FORCEPROP 1 LASTPIN (9075 12900) $PN 1
R 1
J 0
(9095 12910);
DISPLAY 0.787234 (9095 12910);
PAINT MONO (9095 12910);
DISPLAY INVISIBLE (9095 12910);
FORCEPROP 1 LASTPIN (9275 12900) $PN 2
R 1
J 0
(9295 12910);
DISPLAY 0.787234 (9295 12910);
PAINT MONO (9295 12910);
DISPLAY INVISIBLE (9295 12910);
FORCEADD Q_RES..2
(9575 13075);
FORCEPROP 1 LAST PART_NUMBER CS41002FB09
J 0
(9615 12950);
DISPLAY 0.510638 (9615 12950);
DISPLAY INVISIBLE (9615 12950);
FORCEPROP 2 LAST ROOM NIC1_P3V3_BOM1
J 0
(9625 13250);
DISPLAY 0.510638 (9625 13250);
FORCEPROP 1 LAST PACK_TYPE 0402LF
J 0
(9615 12900);
DISPLAY 0.510638 (9615 12900);
FORCEPROP 1 LAST MATERIAL CHIP
J 0
(9615 13000);
DISPLAY 0.510638 (9615 13000);
FORCEPROP 1 LAST VALUE 100K
J 0
(9620 13150);
DISPLAY 0.510638 (9620 13150);
FORCEPROP 1 LAST WATTAGE 1/16W
J 0
(9615 13050);
DISPLAY 0.510638 (9615 13050);
FORCEPROP 1 LAST TOLERANCE 1%
J 0
(9620 13100);
DISPLAY 0.510638 (9620 13100);
FORCEPROP 1 LAST LOCATION R3796
J 0
(9620 13200);
DISPLAY 0.638298 (9620 13200);
FORCEPROP 1 LASTPIN (9575 13175) $PN 1
J 0
(9580 13137);
DISPLAY 0.787234 (9580 13137);
PAINT MONO (9580 13137);
FORCEPROP 1 LASTPIN (9575 12975) $PN 2
J 0
(9580 12985);
DISPLAY 0.787234 (9580 12985);
PAINT MONO (9580 12985);
FORCEPROP 2 LAST CDS_LIB pure_quanta
J 0
(9575 13075);
DISPLAY INVISIBLE (9575 13075);
FORCEPROP 1 LAST PATH I108
J 0
(9625 13250);
DISPLAY 0.978723 (9625 13250);
PAINT WHITE (9625 13250);
DISPLAY INVISIBLE (9625 13250);
FORCEPROP 0 LAST $SEC 1
J 0
(9625 13250);
DISPLAY 0.680851 (9625 13250);
PAINT MONO (9625 13250);
DISPLAY INVISIBLE (9625 13250);
FORCEPROP 0 LAST CDS_SEC 1
J 0
(9625 13250);
DISPLAY 1.021277 (9625 13250);
DISPLAY INVISIBLE (9625 13250);
FORCEADD VCCAUX15..1
(9775 13350);
FORCEPROP 3 LASTPIN (9775 13300) SIG_NAME P3V3_AUX\g
J 0
(9785 13310);
DISPLAY 0.659574 (9785 13310);
PAINT MONO (9785 13310);
DISPLAY INVISIBLE (9785 13310);
FORCEPROP 1 LAST HDL_POWER P3V3_AUX
J 1
(9775 13400);
DISPLAY 0.723404 (9775 13400);
PAINT GREEN (9775 13400);
FORCEPROP 2 LAST CDS_LIB logical_power
J 0
(9775 13350);
DISPLAY INVISIBLE (9775 13350);
FORCEPROP 1 LAST PATH I109
J 0
(9825 13375);
DISPLAY 0.872340 (9825 13375);
PAINT AQUA (9825 13375);
DISPLAY INVISIBLE (9825 13375);
FORCEADD OFFPAGE..1
(3625 9375);
FORCEPROP 2 LAST $XR1 165 
J 0
(3253 9375);
DISPLAY 0.638298 (3253 9375);
PAINT MONO (3253 9375);
FORCEPROP 2 LAST $XR0 153 
J 0
(3373 9375);
DISPLAY 0.638298 (3373 9375);
PAINT MONO (3373 9375);
FORCEPROP 1 LAST COMMENT_BODY TRUE
J 0
(3750 9275);
DISPLAY 0.872340 (3750 9275);
PAINT GREEN (3750 9275);
DISPLAY INVISIBLE (3750 9275);
FORCEPROP 1 LAST OFFPAGE TRUE
J 0
(3950 9250);
DISPLAY 0.872340 (3950 9250);
PAINT GREEN (3950 9250);
DISPLAY INVISIBLE (3950 9250);
FORCEPROP 2 LAST CDS_LIB standard
J 0
(3625 9375);
PAINT MONO (3625 9375);
DISPLAY INVISIBLE (3625 9375);
FORCEPROP 2 LAST PATH I11
J 0
(3375 9400);
DISPLAY 1.021277 (3375 9400);
DISPLAY INVISIBLE (3375 9400);
FORCEADD Q_RES..2
(9950 13075);
FORCEPROP 1 LAST PART_NUMBER CS41002FB09
J 0
(9990 12950);
DISPLAY 0.510638 (9990 12950);
DISPLAY INVISIBLE (9990 12950);
FORCEPROP 1 LAST PACK_TYPE 0402LF
J 0
(9990 12900);
DISPLAY 0.510638 (9990 12900);
FORCEPROP 1 LAST MATERIAL CHIP
J 0
(9990 13000);
DISPLAY 0.510638 (9990 13000);
FORCEPROP 2 LAST ROOM NIC1_P3V3_BOM1
J 0
(10000 13250);
DISPLAY 0.510638 (10000 13250);
FORCEPROP 1 LAST VALUE 100K
J 0
(9995 13150);
DISPLAY 0.510638 (9995 13150);
FORCEPROP 1 LAST TOLERANCE 1%
J 0
(9995 13100);
DISPLAY 0.510638 (9995 13100);
FORCEPROP 1 LAST WATTAGE 1/16W
J 0
(9990 13050);
DISPLAY 0.510638 (9990 13050);
FORCEPROP 1 LAST LOCATION R3783
J 0
(9995 13200);
DISPLAY 0.638298 (9995 13200);
FORCEPROP 1 LASTPIN (9950 13175) $PN 1
J 0
(9955 13137);
DISPLAY 0.787234 (9955 13137);
PAINT MONO (9955 13137);
FORCEPROP 1 LASTPIN (9950 12975) $PN 2
J 0
(9955 12985);
DISPLAY 0.787234 (9955 12985);
PAINT MONO (9955 12985);
FORCEPROP 2 LAST CDS_LIB pure_quanta
J 0
(9950 13075);
DISPLAY INVISIBLE (9950 13075);
FORCEPROP 1 LAST PATH I110
J 0
(10000 13250);
DISPLAY 0.978723 (10000 13250);
PAINT WHITE (10000 13250);
DISPLAY INVISIBLE (10000 13250);
FORCEPROP 0 LAST $SEC 1
J 0
(10000 13250);
DISPLAY 0.680851 (10000 13250);
PAINT MONO (10000 13250);
DISPLAY INVISIBLE (10000 13250);
FORCEPROP 0 LAST CDS_SEC 1
J 0
(10000 13250);
DISPLAY 1.021277 (10000 13250);
DISPLAY INVISIBLE (10000 13250);
FORCEADD Q_CAP..1
(9450 13675);
FORCEPROP 1 LAST PART_NUMBER CH4104K1B00
J 0
(9500 13525);
DISPLAY 0.638298 (9500 13525);
DISPLAY INVISIBLE (9500 13525);
FORCEPROP 1 LAST PACK_TYPE 0402
J 0
(9500 13575);
DISPLAY 0.638298 (9500 13575);
FORCEPROP 1 LAST VALUE 0.1UF
J 0
(9500 13725);
DISPLAY 0.638298 (9500 13725);
FORCEPROP 1 LAST VOLTAGE 25V
J 0
(9500 13675);
DISPLAY 0.638298 (9500 13675);
FORCEPROP 1 LAST MATERIAL X7R
J 0
(9500 13625);
DISPLAY 0.638298 (9500 13625);
FORCEPROP 1 LAST LOCATION PC2091
J 0
(9500 13775);
DISPLAY 0.638298 (9500 13775);
FORCEPROP 2 LAST CDS_LIB pure_quanta
J 0
(9450 13675);
DISPLAY INVISIBLE (9450 13675);
FORCEPROP 1 LAST TOLERANCE 10%
J 0
(9500 13625);
DISPLAY 0.978723 (9500 13625);
DISPLAY INVISIBLE (9500 13625);
FORCEPROP 1 LAST PATH I111
J 0
(9500 13825);
DISPLAY 0.978723 (9500 13825);
PAINT WHITE (9500 13825);
DISPLAY INVISIBLE (9500 13825);
FORCEPROP 0 LAST $SEC 1
J 0
(9500 13825);
DISPLAY 0.680851 (9500 13825);
PAINT MONO (9500 13825);
DISPLAY INVISIBLE (9500 13825);
FORCEPROP 0 LAST CDS_SEC 1
J 0
(9500 13825);
DISPLAY 1.021277 (9500 13825);
DISPLAY INVISIBLE (9500 13825);
FORCEPROP 1 LASTPIN (9450 13775) $PN 1
J 0
(9460 13755);
DISPLAY 0.787234 (9460 13755);
PAINT MONO (9460 13755);
DISPLAY INVISIBLE (9460 13755);
FORCEPROP 1 LASTPIN (9450 13575) $PN 2
J 0
(9460 13555);
DISPLAY 0.787234 (9460 13555);
PAINT MONO (9460 13555);
DISPLAY INVISIBLE (9460 13555);
FORCEADD GND..1
(10025 13375);
FORCEPROP 3 LASTPIN (10025 13425) SIG_NAME GND\g
J 0
(10035 13435);
DISPLAY 0.659574 (10035 13435);
PAINT MONO (10035 13435);
DISPLAY INVISIBLE (10035 13435);
FORCEPROP 1 LAST HDL_POWER GND
J 0
(10025 13525);
DISPLAY 0.872340 (10025 13525);
PAINT GREEN (10025 13525);
DISPLAY INVISIBLE (10025 13525);
FORCEPROP 1 LAST SIZE 1B
J 0
(10100 13325);
DISPLAY 0.872340 (10100 13325);
PAINT GREEN (10100 13325);
DISPLAY INVISIBLE (10100 13325);
FORCEPROP 2 LAST CDS_LIB logical_power
J 0
(10025 13375);
DISPLAY INVISIBLE (10025 13375);
FORCEPROP 1 LAST PATH I112
J 0
(10100 13375);
DISPLAY 0.872340 (10100 13375);
PAINT AQUA (10100 13375);
DISPLAY INVISIBLE (10100 13375);
FORCEADD Q_CAP..1
(10025 13675);
FORCEPROP 1 LAST PART_NUMBER CH6103KEA01
J 0
(10075 13525);
DISPLAY 0.638298 (10075 13525);
DISPLAY INVISIBLE (10075 13525);
FORCEPROP 1 LAST VOLTAGE 16V
J 0
(10075 13675);
DISPLAY 0.638298 (10075 13675);
FORCEPROP 1 LAST MATERIAL X6S
J 0
(10075 13625);
DISPLAY 0.638298 (10075 13625);
FORCEPROP 1 LAST VALUE 10UF
J 0
(10075 13725);
DISPLAY 0.638298 (10075 13725);
FORCEPROP 1 LAST PACK_TYPE C0805
J 0
(10075 13575);
DISPLAY 0.638298 (10075 13575);
FORCEPROP 1 LAST LOCATION PC2081
J 0
(10075 13775);
DISPLAY 0.680851 (10075 13775);
FORCEPROP 2 LAST CDS_LIB pure_quanta
J 0
(10025 13675);
DISPLAY INVISIBLE (10025 13675);
FORCEPROP 1 LAST TOLERANCE 10%
J 0
(9814 13635);
DISPLAY 0.787234 (9814 13635);
PAINT GREEN (9814 13635);
DISPLAY INVISIBLE (9814 13635);
FORCEPROP 1 LAST PATH I113
J 0
(10075 13825);
DISPLAY 0.978723 (10075 13825);
PAINT WHITE (10075 13825);
DISPLAY INVISIBLE (10075 13825);
FORCEPROP 0 LAST $SEC 1
J 0
(10075 13825);
DISPLAY INVISIBLE (10075 13825);
FORCEPROP 0 LAST CDS_SEC 1
J 0
(10075 13825);
DISPLAY INVISIBLE (10075 13825);
FORCEPROP 1 LASTPIN (10025 13775) $PN 1
J 0
(10035 13755);
DISPLAY 0.787234 (10035 13755);
PAINT MONO (10035 13755);
DISPLAY INVISIBLE (10035 13755);
FORCEPROP 1 LASTPIN (10025 13575) $PN 2
J 0
(10035 13555);
DISPLAY 0.787234 (10035 13555);
PAINT MONO (10035 13555);
DISPLAY INVISIBLE (10035 13555);
FORCEADD UNIVERSAL_POWER..1
R 2
(10025 13975);
FORCEPROP 3 LASTPIN (10025 13925) SIG_NAME P3V3_OCP_SFF_R\g
J 0
(10035 13935);
DISPLAY 0.659574 (10035 13935);
PAINT MONO (10035 13935);
DISPLAY INVISIBLE (10035 13935);
FORCEPROP 1 LAST HDL_POWER P3V3_OCP_SFF_R
J 1
(10025 14025);
DISPLAY 0.723404 (10025 14025);
PAINT GREEN (10025 14025);
FORCEPROP 2 LAST CDS_LIB logical_power
J 0
(10025 13975);
DISPLAY INVISIBLE (10025 13975);
FORCEPROP 1 LAST PATH I114
J 2
(9975 14000);
DISPLAY 0.872340 (9975 14000);
PAINT AQUA (9975 14000);
DISPLAY INVISIBLE (9975 14000);
FORCEADD OFFPAGE..2
(10275 12800);
PAINT AQUA (10275 12800);
FORCEPROP 2 LAST $XR0 158 
J 0
(10464 12800);
DISPLAY 0.638298 (10464 12800);
PAINT MONO (10464 12800);
FORCEPROP 2 LAST CDS_LIB standard
J 0
(10275 12800);
DISPLAY INVISIBLE (10275 12800);
FORCEPROP 1 LAST COMMENT_BODY TRUE
J 0
(10230 12705);
DISPLAY 0.872340 (10230 12705);
PAINT GREEN (10230 12705);
DISPLAY INVISIBLE (10230 12705);
FORCEPROP 1 LAST OFFPAGE TRUE
J 0
(10600 12675);
DISPLAY 0.872340 (10600 12675);
PAINT AQUA (10600 12675);
DISPLAY INVISIBLE (10600 12675);
FORCEPROP 2 LAST PATH I115
J 0
(10475 12850);
DISPLAY 1.021277 (10475 12850);
DISPLAY INVISIBLE (10475 12850);
FORCEADD OFFPAGE..1
(3625 9475);
FORCEPROP 2 LAST $XR1 165 
J 0
(3253 9475);
DISPLAY 0.638298 (3253 9475);
PAINT MONO (3253 9475);
FORCEPROP 2 LAST $XR0 153 
J 0
(3373 9475);
DISPLAY 0.638298 (3373 9475);
PAINT MONO (3373 9475);
FORCEPROP 1 LAST COMMENT_BODY TRUE
J 0
(3750 9375);
DISPLAY 0.872340 (3750 9375);
PAINT GREEN (3750 9375);
DISPLAY INVISIBLE (3750 9375);
FORCEPROP 1 LAST OFFPAGE TRUE
J 0
(3950 9350);
DISPLAY 0.872340 (3950 9350);
PAINT GREEN (3950 9350);
DISPLAY INVISIBLE (3950 9350);
FORCEPROP 2 LAST CDS_LIB standard
J 0
(3625 9475);
PAINT MONO (3625 9475);
DISPLAY INVISIBLE (3625 9475);
FORCEPROP 2 LAST PATH I12
J 0
(3375 9500);
DISPLAY 1.021277 (3375 9500);
DISPLAY INVISIBLE (3375 9500);
FORCEADD Q_RES..2
(3800 9725);
FORCEPROP 1 LAST PART_NUMBER CS21002FB06
J 0
(3840 9600);
DISPLAY 0.638298 (3840 9600);
DISPLAY INVISIBLE (3840 9600);
FORCEPROP 1 LAST PACK_TYPE 0402LF
J 0
(3840 9600);
DISPLAY 0.510638 (3840 9600);
FORCEPROP 1 LAST VALUE 1K
J 0
(3845 9800);
DISPLAY 0.510638 (3845 9800);
FORCEPROP 1 LAST TOLERANCE 1%
J 0
(3845 9750);
DISPLAY 0.510638 (3845 9750);
FORCEPROP 1 LAST WATTAGE 1/16W
J 0
(3840 9700);
DISPLAY 0.510638 (3840 9700);
FORCEPROP 1 LAST MATERIAL CHIP
J 0
(3840 9650);
DISPLAY 0.510638 (3840 9650);
FORCEPROP 1 LAST LOCATION R1905
J 0
(3845 9850);
DISPLAY 0.510638 (3845 9850);
FORCEPROP 1 LASTPIN (3800 9825) $PN 1
J 0
(3805 9787);
DISPLAY 0.510638 (3805 9787);
PAINT MONO (3805 9787);
FORCEPROP 1 LASTPIN (3800 9625) $PN 2
J 0
(3805 9635);
DISPLAY 0.510638 (3805 9635);
PAINT MONO (3805 9635);
FORCEPROP 2 LAST CDS_LIB pure_quanta
J 0
(3800 9725);
DISPLAY INVISIBLE (3800 9725);
FORCEPROP 1 LAST PATH I13
J 0
(3850 9900);
DISPLAY 0.978723 (3850 9900);
PAINT WHITE (3850 9900);
DISPLAY INVISIBLE (3850 9900);
FORCEPROP 0 LAST $SEC 1
J 0
(3850 9900);
DISPLAY 0.680851 (3850 9900);
PAINT MONO (3850 9900);
DISPLAY INVISIBLE (3850 9900);
FORCEPROP 0 LAST CDS_SEC 1
J 0
(3850 9900);
DISPLAY 1.021277 (3850 9900);
DISPLAY INVISIBLE (3850 9900);
FORCEADD UNIVERSAL_POWER..1
(3800 10025);
FORCEPROP 3 LASTPIN (3800 9975) SIG_NAME P3V3_AUX\g
J 0
(3810 9985);
DISPLAY 0.659574 (3810 9985);
PAINT MONO (3810 9985);
DISPLAY INVISIBLE (3810 9985);
FORCEPROP 1 LAST HDL_POWER P3V3_AUX
J 1
(3800 10075);
DISPLAY 0.510638 (3800 10075);
PAINT GREEN (3800 10075);
FORCEPROP 2 LAST CDS_LIB logical_power
J 0
(3800 10025);
DISPLAY INVISIBLE (3800 10025);
FORCEPROP 1 LAST PATH I14
J 0
(3850 10050);
DISPLAY 0.872340 (3850 10050);
PAINT AQUA (3850 10050);
DISPLAY INVISIBLE (3850 10050);
FORCEADD Q_RES..2
(3375 10850);
FORCEPROP 1 LAST PART_NUMBER CS31002FB08
J 0
(3405 10767);
DISPLAY 0.510638 (3405 10767);
DISPLAY INVISIBLE (3405 10767);
FORCEPROP 1 LAST WATTAGE 1/16W
J 0
(3405 10867);
DISPLAY 0.510638 (3405 10867);
FORCEPROP 1 LAST PACK_TYPE 0402LF
J 0
(3405 10717);
DISPLAY 0.510638 (3405 10717);
FORCEPROP 2 LAST ROOM NIC1_P12V_MAM_MAM_BOM1
J 0
(3425 11050);
DISPLAY 0.510638 (3425 11050);
FORCEPROP 1 LAST VALUE 10K
J 0
(3410 10967);
DISPLAY 0.510638 (3410 10967);
FORCEPROP 1 LAST TOLERANCE 1%
J 0
(3410 10917);
DISPLAY 0.510638 (3410 10917);
FORCEPROP 1 LAST MATERIAL EMPTY
J 0
(3405 10817);
DISPLAY 0.510638 (3405 10817);
PAINT RED (3405 10817);
FORCEPROP 1 LAST $LOCATION R4068
J 0
(3410 11017);
DISPLAY 0.510638 (3410 11017);
FORCEPROP 1 LASTPIN (3375 10950) $PN 1
J 0
(3380 10912);
DISPLAY 0.510638 (3380 10912);
PAINT MONO (3380 10912);
FORCEPROP 1 LASTPIN (3375 10750) $PN 2
J 0
(3380 10760);
DISPLAY 0.510638 (3380 10760);
PAINT MONO (3380 10760);
FORCEPROP 2 LAST ROOM1 NIC1_P12V_MAM_TIC_BOM2
J 0
(3425 11100);
DISPLAY 1.021277 (3425 11100);
DISPLAY INVISIBLE (3425 11100);
FORCEPROP 2 LAST CDS_LIB pure_quanta
J 0
(3375 10850);
DISPLAY INVISIBLE (3375 10850);
FORCEPROP 1 LAST PATH I15
J 0
(3425 11025);
DISPLAY 0.978723 (3425 11025);
PAINT WHITE (3425 11025);
DISPLAY INVISIBLE (3425 11025);
FORCEPROP 0 LAST CDS_LOCATION R4068
J 0
(3425 11050);
DISPLAY 1.021277 (3425 11050);
DISPLAY INVISIBLE (3425 11050);
FORCEPROP 0 LAST $SEC 1
J 0
(3425 11050);
DISPLAY 0.680851 (3425 11050);
PAINT MONO (3425 11050);
DISPLAY INVISIBLE (3425 11050);
FORCEPROP 0 LAST CDS_SEC 1
J 0
(3425 11050);
DISPLAY 1.021277 (3425 11050);
DISPLAY INVISIBLE (3425 11050);
FORCEADD UNIVERSAL_POWER..1
(3375 11100);
FORCEPROP 3 LASTPIN (3375 11050) SIG_NAME P12V_AUX\g
J 0
(3385 11060);
DISPLAY 0.659574 (3385 11060);
PAINT MONO (3385 11060);
DISPLAY INVISIBLE (3385 11060);
FORCEPROP 1 LAST HDL_POWER P12V_AUX
J 1
(3375 11150);
DISPLAY 0.510638 (3375 11150);
PAINT GREEN (3375 11150);
FORCEPROP 2 LAST CDS_LIB logical_power
J 0
(3375 11100);
DISPLAY INVISIBLE (3375 11100);
FORCEPROP 1 LAST PATH I16
J 0
(3425 11125);
DISPLAY 0.872340 (3425 11125);
PAINT AQUA (3425 11125);
DISPLAY INVISIBLE (3425 11125);
FORCEADD MOSFET_NCH_DUAL..2
(4075 10575);
FORCEPROP 1 LAST PART_NUMBER BAM138K0003
J 0
(4226 10481);
DISPLAY 0.510638 (4226 10481);
PAINT GREEN (4226 10481);
DISPLAY INVISIBLE (4226 10481);
FORCEPROP 2 LAST VALUE PJT138K
J 0
(4250 10600);
DISPLAY 0.510638 (4250 10600);
FORCEPROP 2 LAST ROOM NIC1_P12V_MAM_MAM_BOM1
J 0
(4250 10700);
DISPLAY 0.510638 (4250 10700);
FORCEPROP 2 LAST PART_TYPE SMLF
J 0
(4250 10650);
DISPLAY 0.510638 (4250 10650);
FORCEPROP 1 LAST MATERIAL EMPTY
J 0
(4226 10426);
DISPLAY 0.510638 (4226 10426);
PAINT RED (4226 10426);
FORCEPROP 1 LAST $LOCATION Q123
J 0
(4226 10551);
DISPLAY 0.510638 (4226 10551);
PAINT GREEN (4226 10551);
FORCEPROP 0 LASTPIN (4125 10775) $PN 3
R 1
J 0
(4115 10785);
DISPLAY 0.510638 (4115 10785);
PAINT MONO (4115 10785);
FORCEPROP 0 LASTPIN (3875 10525) $PN 5
J 2
(3865 10535);
DISPLAY 0.510638 (3865 10535);
PAINT MONO (3865 10535);
FORCEPROP 0 LASTPIN (4125 10375) $PN 4
R 1
J 2
(4115 10365);
DISPLAY 0.510638 (4115 10365);
PAINT MONO (4115 10365);
FORCEPROP 2 LAST ROOM1 NIC1_P12V_MAM_TIC_BOM2
J 0
(4250 10750);
DISPLAY 1.021277 (4250 10750);
DISPLAY INVISIBLE (4250 10750);
FORCEPROP 2 LAST CDS_LIB pure_quanta
J 0
(4075 10575);
DISPLAY INVISIBLE (4075 10575);
FORCEPROP 1 LAST CDS_LMAN_SYM_OUTLINE -150,150,150,-150
J 0
(4075 10575);
DISPLAY 0.468085 (4075 10575);
PAINT GREEN (4075 10575);
DISPLAY INVISIBLE (4075 10575);
FORCEPROP 1 LAST NEEDS_NO_SIZE TRUE
J 0
(4225 10466);
DISPLAY 0.468085 (4225 10466);
PAINT GREEN (4225 10466);
DISPLAY INVISIBLE (4225 10466);
FORCEPROP 1 LAST PATH I17
J 0
(4225 10425);
DISPLAY 0.723404 (4225 10425);
PAINT GREEN (4225 10425);
DISPLAY INVISIBLE (4225 10425);
FORCEPROP 0 LAST CDS_LOCATION Q123
J 0
(4250 10700);
DISPLAY 1.021277 (4250 10700);
DISPLAY INVISIBLE (4250 10700);
FORCEPROP 0 LAST $SEC 2
J 0
(4250 10700);
DISPLAY 0.680851 (4250 10700);
PAINT MONO (4250 10700);
DISPLAY INVISIBLE (4250 10700);
FORCEPROP 0 LAST CDS_SEC 2
J 0
(4250 10700);
DISPLAY 1.021277 (4250 10700);
DISPLAY INVISIBLE (4250 10700);
FORCEADD GND..1
(3550 11275);
FORCEPROP 3 LASTPIN (3550 11325) SIG_NAME GND\g
J 0
(3560 11335);
DISPLAY 0.659574 (3560 11335);
PAINT MONO (3560 11335);
DISPLAY INVISIBLE (3560 11335);
FORCEPROP 1 LAST HDL_POWER GND
J 0
(3550 11425);
DISPLAY 0.872340 (3550 11425);
PAINT GREEN (3550 11425);
DISPLAY INVISIBLE (3550 11425);
FORCEPROP 1 LAST SIZE 1B
J 0
(3625 11225);
DISPLAY 0.872340 (3625 11225);
PAINT GREEN (3625 11225);
DISPLAY INVISIBLE (3625 11225);
FORCEPROP 2 LAST CDS_LIB logical_power
J 0
(3550 11275);
DISPLAY INVISIBLE (3550 11275);
FORCEPROP 1 LAST PATH I18
J 0
(3625 11275);
DISPLAY 0.872340 (3625 11275);
PAINT AQUA (3625 11275);
DISPLAY INVISIBLE (3625 11275);
FORCEADD Q_RES..1
(3175 11850);
FORCEPROP 1 LAST PART_NUMBER CS00002JB13
J 0
(2875 11775);
DISPLAY 0.595745 (2875 11775);
DISPLAY INVISIBLE (2875 11775);
FORCEPROP 1 LAST MATERIAL CHIP
J 0
(3050 11725);
DISPLAY 0.595745 (3050 11725);
FORCEPROP 1 LAST TOLERANCE 5%
J 0
(3350 11850);
DISPLAY 0.595745 (3350 11850);
FORCEPROP 1 LAST PACK_TYPE 0402LF
J 0
(3250 11775);
DISPLAY 0.595745 (3250 11775);
FORCEPROP 1 LAST VALUE 0
J 2
(3325 11850);
DISPLAY 0.595745 (3325 11850);
FORCEPROP 1 LAST WATTAGE 1/16W
J 2
(3375 11725);
DISPLAY 0.595745 (3375 11725);
FORCEPROP 1 LAST $LOCATION R5487
J 0
(2950 11850);
DISPLAY 0.638298 (2950 11850);
FORCEPROP 2 LAST CDS_LIB pure_quanta
J 0
(3175 11850);
DISPLAY INVISIBLE (3175 11850);
FORCEPROP 1 LAST PATH I19
J 0
(3125 12000);
DISPLAY 0.978723 (3125 12000);
PAINT WHITE (3125 12000);
DISPLAY INVISIBLE (3125 12000);
FORCEPROP 0 LAST CDS_LOCATION R5487
J 0
(3250 11925);
DISPLAY INVISIBLE (3250 11925);
FORCEPROP 0 LAST $SEC 1
J 0
(3250 11925);
DISPLAY INVISIBLE (3250 11925);
FORCEPROP 0 LAST CDS_SEC 1
J 0
(3250 11925);
DISPLAY INVISIBLE (3250 11925);
FORCEPROP 1 LASTPIN (3075 11850) $PN 1
J 0
(3087 11862);
DISPLAY 0.787234 (3087 11862);
PAINT MONO (3087 11862);
DISPLAY INVISIBLE (3087 11862);
FORCEPROP 1 LASTPIN (3275 11850) $PN 2
J 0
(3237 11862);
DISPLAY 0.787234 (3237 11862);
PAINT MONO (3237 11862);
DISPLAY INVISIBLE (3237 11862);
FORCEADD UNIVERSAL_GND..1
(4775 8225);
FORCEPROP 3 LASTPIN (4775 8275) SIG_NAME GND\g
J 0
(4785 8285);
DISPLAY 0.659574 (4785 8285);
PAINT MONO (4785 8285);
DISPLAY INVISIBLE (4785 8285);
FORCEPROP 1 LAST HDL_POWER GND
J 1
(4800 8150);
DISPLAY 0.872340 (4800 8150);
PAINT GREEN (4800 8150);
DISPLAY INVISIBLE (4800 8150);
FORCEPROP 2 LAST CDS_LIB logical_power
J 0
(4775 8225);
PAINT MONO (4775 8225);
DISPLAY INVISIBLE (4775 8225);
FORCEPROP 1 LAST PATH I2
J 0
(4850 8225);
DISPLAY 0.872340 (4850 8225);
PAINT AQUA (4850 8225);
DISPLAY INVISIBLE (4850 8225);
FORCEADD Q_RES..2
(3550 11525);
FORCEPROP 1 LAST PART_NUMBER CS24702JB10
J 0
(3590 11350);
DISPLAY 0.638298 (3590 11350);
DISPLAY INVISIBLE (3590 11350);
FORCEPROP 1 LAST WATTAGE 1/16W
J 0
(3590 11500);
DISPLAY 0.638298 (3590 11500);
FORCEPROP 1 LAST MATERIAL CHIP
J 0
(3590 11450);
DISPLAY 0.638298 (3590 11450);
FORCEPROP 1 LAST PACK_TYPE 0402LF
J 0
(3590 11400);
DISPLAY 0.638298 (3590 11400);
FORCEPROP 1 LAST TOLERANCE 5%
J 0
(3595 11550);
DISPLAY 0.638298 (3595 11550);
FORCEPROP 1 LAST VALUE 4.7K
J 0
(3595 11600);
DISPLAY 0.638298 (3595 11600);
FORCEPROP 1 LAST $LOCATION R4069
J 0
(3595 11650);
DISPLAY 0.978723 (3595 11650);
FORCEPROP 1 LASTPIN (3550 11625) $PN 1
J 0
(3555 11587);
DISPLAY 0.787234 (3555 11587);
PAINT MONO (3555 11587);
FORCEPROP 1 LASTPIN (3550 11425) $PN 2
J 0
(3555 11435);
DISPLAY 0.787234 (3555 11435);
PAINT MONO (3555 11435);
FORCEPROP 2 LAST CDS_LIB pure_quanta
J 0
(3550 11525);
DISPLAY INVISIBLE (3550 11525);
FORCEPROP 1 LAST PATH I20
J 0
(3600 11700);
DISPLAY 0.978723 (3600 11700);
PAINT WHITE (3600 11700);
DISPLAY INVISIBLE (3600 11700);
FORCEPROP 0 LAST CDS_LOCATION R4069
J 0
(3600 11700);
DISPLAY 1.021277 (3600 11700);
DISPLAY INVISIBLE (3600 11700);
FORCEPROP 0 LAST $SEC 1
J 0
(3600 11700);
DISPLAY 0.680851 (3600 11700);
PAINT MONO (3600 11700);
DISPLAY INVISIBLE (3600 11700);
FORCEPROP 0 LAST CDS_SEC 1
J 0
(3600 11700);
DISPLAY 1.021277 (3600 11700);
DISPLAY INVISIBLE (3600 11700);
FORCEADD MOSFET_NCH_DUAL..1
(4075 11900);
FORCEPROP 1 LAST PART_NUMBER BAM138K0003
J 0
(4226 11814);
DISPLAY 0.723404 (4226 11814);
PAINT GREEN (4226 11814);
DISPLAY INVISIBLE (4226 11814);
FORCEPROP 2 LAST ROOM NIC1_P3V3_BOM1
J 0
(4250 12000);
DISPLAY 0.808511 (4250 12000);
FORCEPROP 1 LAST MATERIAL IC
J 0
(4226 11749);
DISPLAY 0.723404 (4226 11749);
PAINT GREEN (4226 11749);
FORCEPROP 2 LAST PART_TYPE SMLF
J 0
(4250 11950);
DISPLAY 1.021277 (4250 11950);
FORCEPROP 2 LAST VALUE PJT138K
J 0
(4250 11900);
DISPLAY 1.021277 (4250 11900);
FORCEPROP 1 LAST $LOCATION Q124
J 0
(4250 11850);
DISPLAY 0.723404 (4250 11850);
PAINT GREEN (4250 11850);
FORCEPROP 0 LASTPIN (4125 12100) $PN 6
R 1
J 0
(4115 12110);
DISPLAY 0.680851 (4115 12110);
PAINT MONO (4115 12110);
FORCEPROP 0 LASTPIN (3875 11850) $PN 2
J 2
(3865 11860);
DISPLAY 0.680851 (3865 11860);
PAINT MONO (3865 11860);
FORCEPROP 0 LASTPIN (4125 11700) $PN 1
R 1
J 2
(4115 11690);
DISPLAY 0.680851 (4115 11690);
PAINT MONO (4115 11690);
FORCEPROP 2 LAST CDS_LIB pure_quanta
J 0
(4075 11900);
DISPLAY INVISIBLE (4075 11900);
FORCEPROP 1 LAST CDS_LMAN_SYM_OUTLINE -150,150,150,-150
J 0
(4075 11900);
DISPLAY 0.468085 (4075 11900);
PAINT GREEN (4075 11900);
DISPLAY INVISIBLE (4075 11900);
FORCEPROP 1 LAST NEEDS_NO_SIZE TRUE
J 0
(4075 11899);
DISPLAY 0.468085 (4075 11899);
PAINT GREEN (4075 11899);
DISPLAY INVISIBLE (4075 11899);
FORCEPROP 1 LAST PATH I21
J 0
(4075 11900);
DISPLAY 0.723404 (4075 11900);
PAINT GREEN (4075 11900);
DISPLAY INVISIBLE (4075 11900);
FORCEPROP 0 LAST CDS_LOCATION Q124
J 0
(4250 12025);
DISPLAY 1.021277 (4250 12025);
DISPLAY INVISIBLE (4250 12025);
FORCEPROP 0 LAST $SEC 1
J 0
(4250 12025);
DISPLAY 0.680851 (4250 12025);
PAINT MONO (4250 12025);
DISPLAY INVISIBLE (4250 12025);
FORCEPROP 0 LAST CDS_SEC 1
J 0
(4250 12025);
DISPLAY 1.021277 (4250 12025);
DISPLAY INVISIBLE (4250 12025);
FORCEADD Q_RES..2
(4025 8825);
FORCEPROP 1 LAST PART_NUMBER CS21002FB06
J 0
(4065 8700);
DISPLAY 0.638298 (4065 8700);
DISPLAY INVISIBLE (4065 8700);
FORCEPROP 1 LAST WATTAGE 1/16W
J 0
(4065 8800);
DISPLAY 0.510638 (4065 8800);
FORCEPROP 1 LAST VALUE 1K
J 0
(4070 8900);
DISPLAY 0.510638 (4070 8900);
FORCEPROP 1 LAST TOLERANCE 1%
J 0
(4070 8850);
DISPLAY 0.510638 (4070 8850);
FORCEPROP 1 LAST MATERIAL CHIP
J 0
(4065 8750);
DISPLAY 0.510638 (4065 8750);
FORCEPROP 1 LAST PACK_TYPE 0402LF
J 0
(4065 8700);
DISPLAY 0.510638 (4065 8700);
FORCEPROP 1 LAST LOCATION R1908
J 0
(4070 8950);
DISPLAY 0.510638 (4070 8950);
FORCEPROP 1 LASTPIN (4025 8925) $PN 1
J 0
(4030 8887);
DISPLAY 0.510638 (4030 8887);
PAINT MONO (4030 8887);
FORCEPROP 1 LASTPIN (4025 8725) $PN 2
J 0
(4030 8735);
DISPLAY 0.510638 (4030 8735);
PAINT MONO (4030 8735);
FORCEPROP 2 LAST CDS_LIB pure_quanta
J 0
(4025 8825);
DISPLAY INVISIBLE (4025 8825);
FORCEPROP 1 LAST PATH I22
J 0
(4075 9000);
DISPLAY 0.978723 (4075 9000);
PAINT WHITE (4075 9000);
DISPLAY INVISIBLE (4075 9000);
FORCEPROP 0 LAST $SEC 1
J 0
(4075 9000);
DISPLAY 0.680851 (4075 9000);
PAINT MONO (4075 9000);
DISPLAY INVISIBLE (4075 9000);
FORCEPROP 0 LAST CDS_SEC 1
J 0
(4075 9000);
DISPLAY 1.021277 (4075 9000);
DISPLAY INVISIBLE (4075 9000);
FORCEADD 74LVC2G07DW7..1
(5175 8525);
FORCEPROP 1 LAST PART_NUMBER AL002G07003
J 0
(5006 8759);
DISPLAY 0.510638 (5006 8759);
PAINT GREEN (5006 8759);
DISPLAY INVISIBLE (5006 8759);
FORCEPROP 2 LAST VALUE 74LVC2G07DW-7
J 0
(5025 8950);
DISPLAY 0.510638 (5025 8950);
FORCEPROP 2 LAST PART_TYPE SMLF
J 0
(5025 9000);
DISPLAY 0.510638 (5025 9000);
FORCEPROP 1 LAST MATERIAL IC
J 0
(5006 8632);
DISPLAY 0.510638 (5006 8632);
PAINT GREEN (5006 8632);
FORCEPROP 1 LAST $LOCATION U212
J 0
(5006 8906);
DISPLAY 0.510638 (5006 8906);
PAINT GREEN (5006 8906);
FORCEPROP 0 LASTPIN (4850 8575) $PN 1
J 2
(4840 8585);
DISPLAY 0.510638 (4840 8585);
PAINT MONO (4840 8585);
FORCEPROP 0 LASTPIN (5500 8575) $PN 6
J 0
(5510 8585);
DISPLAY 0.510638 (5510 8585);
PAINT MONO (5510 8585);
FORCEPROP 0 LASTPIN (4850 8475) $PN 3
J 2
(4840 8485);
DISPLAY 0.510638 (4840 8485);
PAINT MONO (4840 8485);
FORCEPROP 0 LASTPIN (5500 8475) $PN 4
J 0
(5510 8485);
DISPLAY 0.510638 (5510 8485);
PAINT MONO (5510 8485);
FORCEPROP 0 LASTPIN (4850 8525) $PN 2
J 2
(4840 8535);
DISPLAY 0.510638 (4840 8535);
PAINT MONO (4840 8535);
FORCEPROP 0 LASTPIN (5500 8525) $PN 5
J 0
(5510 8535);
DISPLAY 0.510638 (5510 8535);
PAINT MONO (5510 8535);
FORCEPROP 1 LAST NEEDS_NO_SIZE TRUE
J 0
(5175 8525);
DISPLAY 0.723404 (5175 8525);
PAINT GREEN (5175 8525);
DISPLAY INVISIBLE (5175 8525);
FORCEPROP 1 LAST CDS_LMAN_SYM_OUTLINE -175,100,175,-100
J 0
(5175 8525);
DISPLAY 0.468085 (5175 8525);
PAINT GREEN (5175 8525);
DISPLAY INVISIBLE (5175 8525);
FORCEPROP 2 LAST CDS_LIB pure_quanta
J 0
(5175 8525);
DISPLAY INVISIBLE (5175 8525);
FORCEPROP 1 LAST PATH I23
J 0
(5175 8525);
DISPLAY 0.723404 (5175 8525);
PAINT GREEN (5175 8525);
DISPLAY INVISIBLE (5175 8525);
FORCEPROP 0 LAST CDS_LOCATION U212
J 0
(5025 9050);
DISPLAY 1.021277 (5025 9050);
DISPLAY INVISIBLE (5025 9050);
FORCEPROP 0 LAST $SEC 1
J 0
(5025 9050);
DISPLAY 0.680851 (5025 9050);
PAINT MONO (5025 9050);
DISPLAY INVISIBLE (5025 9050);
FORCEPROP 0 LAST CDS_SEC 1
J 0
(5025 9050);
DISPLAY 1.021277 (5025 9050);
DISPLAY INVISIBLE (5025 9050);
FORCEADD UNIVERSAL_GND..1
(4775 9150);
FORCEPROP 3 LASTPIN (4775 9200) SIG_NAME GND\g
J 0
(4785 9210);
DISPLAY 0.659574 (4785 9210);
PAINT MONO (4785 9210);
DISPLAY INVISIBLE (4785 9210);
FORCEPROP 1 LAST HDL_POWER GND
J 1
(4800 9075);
DISPLAY 0.872340 (4800 9075);
PAINT GREEN (4800 9075);
DISPLAY INVISIBLE (4800 9075);
FORCEPROP 2 LAST CDS_LIB logical_power
J 0
(4775 9150);
PAINT MONO (4775 9150);
DISPLAY INVISIBLE (4775 9150);
FORCEPROP 1 LAST PATH I24
J 0
(4850 9150);
DISPLAY 0.872340 (4850 9150);
PAINT AQUA (4850 9150);
DISPLAY INVISIBLE (4850 9150);
FORCEADD Q_RES..2
(4025 9725);
FORCEPROP 1 LAST PART_NUMBER CS21002FB06
J 0
(4065 9600);
DISPLAY 0.638298 (4065 9600);
DISPLAY INVISIBLE (4065 9600);
FORCEPROP 1 LAST MATERIAL CHIP
J 0
(4065 9650);
DISPLAY 0.510638 (4065 9650);
FORCEPROP 1 LAST TOLERANCE 1%
J 0
(4070 9750);
DISPLAY 0.510638 (4070 9750);
FORCEPROP 1 LAST VALUE 1K
J 0
(4070 9800);
DISPLAY 0.510638 (4070 9800);
FORCEPROP 1 LAST PACK_TYPE 0402LF
J 0
(4065 9600);
DISPLAY 0.510638 (4065 9600);
FORCEPROP 1 LAST WATTAGE 1/16W
J 0
(4065 9700);
DISPLAY 0.510638 (4065 9700);
FORCEPROP 1 LAST LOCATION R1907
J 0
(4070 9850);
DISPLAY 0.510638 (4070 9850);
FORCEPROP 1 LASTPIN (4025 9825) $PN 1
J 0
(4030 9787);
DISPLAY 0.510638 (4030 9787);
PAINT MONO (4030 9787);
FORCEPROP 1 LASTPIN (4025 9625) $PN 2
J 0
(4030 9635);
DISPLAY 0.510638 (4030 9635);
PAINT MONO (4030 9635);
FORCEPROP 2 LAST CDS_LIB pure_quanta
J 0
(4025 9725);
DISPLAY INVISIBLE (4025 9725);
FORCEPROP 1 LAST PATH I25
J 0
(4075 9900);
DISPLAY 0.978723 (4075 9900);
PAINT WHITE (4075 9900);
DISPLAY INVISIBLE (4075 9900);
FORCEPROP 0 LAST $SEC 1
J 0
(4075 9900);
DISPLAY 0.680851 (4075 9900);
PAINT MONO (4075 9900);
DISPLAY INVISIBLE (4075 9900);
FORCEPROP 0 LAST CDS_SEC 1
J 0
(4075 9900);
DISPLAY 1.021277 (4075 9900);
DISPLAY INVISIBLE (4075 9900);
FORCEADD 74LVC2G07DW7..1
(5175 9425);
FORCEPROP 1 LAST PART_NUMBER AL002G07003
J 0
(5006 9659);
DISPLAY 0.510638 (5006 9659);
PAINT GREEN (5006 9659);
DISPLAY INVISIBLE (5006 9659);
FORCEPROP 2 LAST VALUE 74LVC2G07DW-7
J 0
(5025 9850);
DISPLAY 0.510638 (5025 9850);
FORCEPROP 2 LAST PART_TYPE SMLF
J 0
(5025 9900);
DISPLAY 0.510638 (5025 9900);
FORCEPROP 1 LAST MATERIAL IC
J 0
(5006 9532);
DISPLAY 0.510638 (5006 9532);
PAINT GREEN (5006 9532);
FORCEPROP 1 LAST $LOCATION U211
J 0
(5006 9806);
DISPLAY 0.510638 (5006 9806);
PAINT GREEN (5006 9806);
FORCEPROP 0 LASTPIN (4850 9475) $PN 1
J 2
(4840 9485);
DISPLAY 0.510638 (4840 9485);
PAINT MONO (4840 9485);
FORCEPROP 0 LASTPIN (5500 9475) $PN 6
J 0
(5510 9485);
DISPLAY 0.510638 (5510 9485);
PAINT MONO (5510 9485);
FORCEPROP 0 LASTPIN (4850 9375) $PN 3
J 2
(4840 9385);
DISPLAY 0.510638 (4840 9385);
PAINT MONO (4840 9385);
FORCEPROP 0 LASTPIN (5500 9375) $PN 4
J 0
(5510 9385);
DISPLAY 0.510638 (5510 9385);
PAINT MONO (5510 9385);
FORCEPROP 0 LASTPIN (4850 9425) $PN 2
J 2
(4840 9435);
DISPLAY 0.510638 (4840 9435);
PAINT MONO (4840 9435);
FORCEPROP 0 LASTPIN (5500 9425) $PN 5
J 0
(5510 9435);
DISPLAY 0.510638 (5510 9435);
PAINT MONO (5510 9435);
FORCEPROP 1 LAST NEEDS_NO_SIZE TRUE
J 0
(5175 9425);
DISPLAY 0.723404 (5175 9425);
PAINT GREEN (5175 9425);
DISPLAY INVISIBLE (5175 9425);
FORCEPROP 1 LAST CDS_LMAN_SYM_OUTLINE -175,100,175,-100
J 0
(5175 9425);
DISPLAY 0.468085 (5175 9425);
PAINT GREEN (5175 9425);
DISPLAY INVISIBLE (5175 9425);
FORCEPROP 2 LAST CDS_LIB pure_quanta
J 0
(5175 9425);
DISPLAY INVISIBLE (5175 9425);
FORCEPROP 1 LAST PATH I26
J 0
(5175 9425);
DISPLAY 0.723404 (5175 9425);
PAINT GREEN (5175 9425);
DISPLAY INVISIBLE (5175 9425);
FORCEPROP 0 LAST CDS_LOCATION U211
J 0
(5025 9950);
DISPLAY 1.021277 (5025 9950);
DISPLAY INVISIBLE (5025 9950);
FORCEPROP 0 LAST $SEC 1
J 0
(5025 9950);
DISPLAY 0.680851 (5025 9950);
PAINT MONO (5025 9950);
DISPLAY INVISIBLE (5025 9950);
FORCEPROP 0 LAST CDS_SEC 1
J 0
(5025 9950);
DISPLAY 1.021277 (5025 9950);
DISPLAY INVISIBLE (5025 9950);
FORCEADD Q_CAP..1
(5850 8350);
FORCEPROP 1 LAST PART_NUMBER CH4104K1B00
J 0
(5900 8200);
DISPLAY 0.510638 (5900 8200);
DISPLAY INVISIBLE (5900 8200);
FORCEPROP 1 LAST VALUE 0.1UF
J 0
(5900 8400);
DISPLAY 0.510638 (5900 8400);
FORCEPROP 1 LAST MATERIAL X7R
J 0
(5900 8250);
DISPLAY 0.510638 (5900 8250);
FORCEPROP 1 LAST VOLTAGE 25V
J 0
(5900 8350);
DISPLAY 0.510638 (5900 8350);
FORCEPROP 1 LAST TOLERANCE 10%
J 0
(5900 8300);
DISPLAY 0.510638 (5900 8300);
FORCEPROP 1 LAST PACK_TYPE 0402
J 0
(5900 8150);
DISPLAY 0.510638 (5900 8150);
FORCEPROP 1 LAST $LOCATION C593
J 0
(5900 8450);
DISPLAY 0.510638 (5900 8450);
FORCEPROP 1 LASTPIN (5850 8450) $PN 1
J 0
(5860 8430);
DISPLAY 0.510638 (5860 8430);
FORCEPROP 1 LASTPIN (5850 8250) $PN 2
J 0
(5860 8230);
DISPLAY 0.510638 (5860 8230);
FORCEPROP 2 LAST CDS_LIB pure_quanta
J 0
(5850 8350);
PAINT MONO (5850 8350);
DISPLAY INVISIBLE (5850 8350);
FORCEPROP 1 LAST PATH I27
J 0
(5900 8500);
DISPLAY 0.978723 (5900 8500);
PAINT WHITE (5900 8500);
DISPLAY INVISIBLE (5900 8500);
FORCEPROP 2 LAST CDS_LOCATION C593
J 0
(5900 8550);
DISPLAY 1.021277 (5900 8550);
DISPLAY INVISIBLE (5900 8550);
FORCEPROP 2 LAST $SEC 1
J 0
(5900 8550);
DISPLAY 0.680851 (5900 8550);
PAINT MONO (5900 8550);
DISPLAY INVISIBLE (5900 8550);
FORCEPROP 2 LAST CDS_SEC 1
J 0
(5900 8550);
DISPLAY 1.021277 (5900 8550);
DISPLAY INVISIBLE (5900 8550);
FORCEADD UNIVERSAL_POWER..1
(5850 8625);
FORCEPROP 3 LASTPIN (5850 8575) SIG_NAME P3V3_AUX\g
J 0
(5860 8585);
DISPLAY 0.659574 (5860 8585);
PAINT MONO (5860 8585);
DISPLAY INVISIBLE (5860 8585);
FORCEPROP 1 LAST HDL_POWER P3V3_AUX
J 1
(5850 8675);
DISPLAY 0.510638 (5850 8675);
PAINT GREEN (5850 8675);
FORCEPROP 2 LAST CDS_LIB logical_power
J 0
(5850 8625);
PAINT MONO (5850 8625);
DISPLAY INVISIBLE (5850 8625);
FORCEPROP 1 LAST PATH I28
J 0
(5900 8650);
DISPLAY 0.872340 (5900 8650);
PAINT AQUA (5900 8650);
DISPLAY INVISIBLE (5900 8650);
FORCEADD UNIVERSAL_GND..1
(5850 9050);
FORCEPROP 3 LASTPIN (5850 9100) SIG_NAME GND\g
J 0
(5860 9110);
DISPLAY 0.659574 (5860 9110);
PAINT MONO (5860 9110);
DISPLAY INVISIBLE (5860 9110);
FORCEPROP 1 LAST HDL_POWER GND
J 1
(5875 8975);
DISPLAY 0.872340 (5875 8975);
PAINT GREEN (5875 8975);
DISPLAY INVISIBLE (5875 8975);
FORCEPROP 2 LAST CDS_LIB logical_power
J 0
(5850 9050);
PAINT MONO (5850 9050);
DISPLAY INVISIBLE (5850 9050);
FORCEPROP 1 LAST PATH I29
J 0
(5925 9050);
DISPLAY 0.872340 (5925 9050);
PAINT AQUA (5925 9050);
DISPLAY INVISIBLE (5925 9050);
FORCEADD OFFPAGE..1
(2025 11850);
PAINT AQUA (2025 11850);
FORCEPROP 2 LAST $XR2 238 
J 0
(1533 11850);
DISPLAY 0.638298 (1533 11850);
PAINT MONO (1533 11850);
FORCEPROP 2 LAST $XR1 157 
J 0
(1653 11850);
DISPLAY 0.638298 (1653 11850);
PAINT MONO (1653 11850);
FORCEPROP 2 LAST $XR0 158 
J 0
(1773 11850);
DISPLAY 0.638298 (1773 11850);
PAINT MONO (1773 11850);
FORCEPROP 1 LAST OFFPAGE TRUE
J 0
(2350 11725);
DISPLAY 0.872340 (2350 11725);
PAINT AQUA (2350 11725);
DISPLAY INVISIBLE (2350 11725);
FORCEPROP 1 LAST COMMENT_BODY TRUE
J 0
(2150 11750);
DISPLAY 0.872340 (2150 11750);
PAINT GREEN (2150 11750);
DISPLAY INVISIBLE (2150 11750);
FORCEPROP 2 LAST CDS_LIB standard
J 0
(2025 11850);
DISPLAY INVISIBLE (2025 11850);
FORCEPROP 2 LAST PATH I3
J 0
(1775 11900);
DISPLAY 1.021277 (1775 11900);
DISPLAY INVISIBLE (1775 11900);
FORCEADD Q_CAP..1
(5850 9250);
FORCEPROP 1 LAST PART_NUMBER CH4104K1B00
J 0
(5900 9100);
DISPLAY 0.510638 (5900 9100);
DISPLAY INVISIBLE (5900 9100);
FORCEPROP 1 LAST VALUE 0.1UF
J 0
(5900 9300);
DISPLAY 0.510638 (5900 9300);
FORCEPROP 1 LAST VOLTAGE 25V
J 0
(5900 9250);
DISPLAY 0.510638 (5900 9250);
FORCEPROP 1 LAST PACK_TYPE 0402
J 0
(5900 9050);
DISPLAY 0.510638 (5900 9050);
FORCEPROP 1 LAST TOLERANCE 10%
J 0
(5900 9200);
DISPLAY 0.510638 (5900 9200);
FORCEPROP 1 LAST MATERIAL X7R
J 0
(5900 9150);
DISPLAY 0.510638 (5900 9150);
FORCEPROP 1 LAST $LOCATION C592
J 0
(5900 9350);
DISPLAY 0.510638 (5900 9350);
FORCEPROP 1 LASTPIN (5850 9350) $PN 1
J 0
(5860 9330);
DISPLAY 0.510638 (5860 9330);
FORCEPROP 1 LASTPIN (5850 9150) $PN 2
J 0
(5860 9130);
DISPLAY 0.510638 (5860 9130);
FORCEPROP 2 LAST CDS_LIB pure_quanta
J 0
(5850 9250);
PAINT MONO (5850 9250);
DISPLAY INVISIBLE (5850 9250);
FORCEPROP 1 LAST PATH I30
J 0
(5900 9400);
DISPLAY 0.978723 (5900 9400);
PAINT WHITE (5900 9400);
DISPLAY INVISIBLE (5900 9400);
FORCEPROP 2 LAST CDS_LOCATION C592
J 0
(5900 9450);
DISPLAY 1.021277 (5900 9450);
DISPLAY INVISIBLE (5900 9450);
FORCEPROP 2 LAST $SEC 1
J 0
(5900 9450);
DISPLAY 0.680851 (5900 9450);
PAINT MONO (5900 9450);
DISPLAY INVISIBLE (5900 9450);
FORCEPROP 2 LAST CDS_SEC 1
J 0
(5900 9450);
DISPLAY 1.021277 (5900 9450);
DISPLAY INVISIBLE (5900 9450);
FORCEADD UNIVERSAL_POWER..1
(5850 9525);
FORCEPROP 3 LASTPIN (5850 9475) SIG_NAME P3V3_AUX\g
J 0
(5860 9485);
DISPLAY 0.659574 (5860 9485);
PAINT MONO (5860 9485);
DISPLAY INVISIBLE (5860 9485);
FORCEPROP 1 LAST HDL_POWER P3V3_AUX
J 1
(5850 9575);
DISPLAY 0.510638 (5850 9575);
PAINT GREEN (5850 9575);
FORCEPROP 2 LAST CDS_LIB logical_power
J 0
(5850 9525);
PAINT MONO (5850 9525);
DISPLAY INVISIBLE (5850 9525);
FORCEPROP 1 LAST PATH I31
J 0
(5900 9550);
DISPLAY 0.872340 (5900 9550);
PAINT AQUA (5900 9550);
DISPLAY INVISIBLE (5900 9550);
FORCEADD GND..1
(5925 9925);
FORCEPROP 3 LASTPIN (5925 9975) SIG_NAME GND\g
J 0
(5935 9985);
DISPLAY 0.659574 (5935 9985);
PAINT MONO (5935 9985);
DISPLAY INVISIBLE (5935 9985);
FORCEPROP 1 LAST HDL_POWER GND
J 0
(5925 10075);
DISPLAY 0.872340 (5925 10075);
PAINT GREEN (5925 10075);
DISPLAY INVISIBLE (5925 10075);
FORCEPROP 1 LAST SIZE 1B
J 0
(6000 9875);
DISPLAY 0.872340 (6000 9875);
PAINT GREEN (6000 9875);
DISPLAY INVISIBLE (6000 9875);
FORCEPROP 2 LAST CDS_LIB logical_power
J 0
(5925 9925);
DISPLAY INVISIBLE (5925 9925);
FORCEPROP 1 LAST PATH I32
J 0
(6000 9925);
DISPLAY 0.872340 (6000 9925);
PAINT AQUA (6000 9925);
DISPLAY INVISIBLE (6000 9925);
FORCEADD Q_RES..2
(5925 10175);
FORCEPROP 1 LAST PART_NUMBER CS31502FB05
J 0
(5975 10125);
DISPLAY 0.510638 (5975 10125);
DISPLAY INVISIBLE (5975 10125);
FORCEPROP 1 LAST WATTAGE 1/16W
J 0
(5975 10175);
DISPLAY 0.510638 (5975 10175);
FORCEPROP 2 LAST ROOM NIC1_P12V_MAM_MAM_BOM1
J 0
(5975 10050);
DISPLAY 0.510638 (5975 10050);
FORCEPROP 1 LAST MATERIAL EMPTY
J 0
(5975 10150);
DISPLAY 0.510638 (5975 10150);
PAINT RED (5975 10150);
FORCEPROP 1 LAST PACK_TYPE 0402LF
J 0
(5975 10100);
DISPLAY 0.510638 (5975 10100);
FORCEPROP 1 LAST TOLERANCE 1%
J 0
(5975 10200);
DISPLAY 0.510638 (5975 10200);
FORCEPROP 1 LAST VALUE 15K
J 0
(5975 10225);
DISPLAY 0.510638 (5975 10225);
FORCEPROP 1 LAST LOCATION PR3788
J 0
(5975 10250);
DISPLAY 0.510638 (5975 10250);
FORCEPROP 2 LAST ROOM1 NIC1_P12V_MAM_TIC_BOM2
J 0
(5975 10350);
DISPLAY 1.021277 (5975 10350);
DISPLAY INVISIBLE (5975 10350);
FORCEPROP 2 LAST CDS_LIB pure_quanta
J 0
(5925 10175);
DISPLAY INVISIBLE (5925 10175);
FORCEPROP 1 LAST PATH I33
J 0
(5975 10350);
DISPLAY 0.978723 (5975 10350);
PAINT WHITE (5975 10350);
DISPLAY INVISIBLE (5975 10350);
FORCEPROP 0 LAST $SEC 1
J 0
(5975 10300);
DISPLAY 0.680851 (5975 10300);
PAINT MONO (5975 10300);
DISPLAY INVISIBLE (5975 10300);
FORCEPROP 0 LAST CDS_SEC 1
J 0
(5975 10300);
DISPLAY 1.021277 (5975 10300);
DISPLAY INVISIBLE (5975 10300);
FORCEPROP 1 LASTPIN (5925 10275) $PN 1
J 0
(5930 10237);
DISPLAY 0.787234 (5930 10237);
PAINT MONO (5930 10237);
DISPLAY INVISIBLE (5930 10237);
FORCEPROP 1 LASTPIN (5925 10075) $PN 2
J 0
(5930 10085);
DISPLAY 0.787234 (5930 10085);
PAINT MONO (5930 10085);
DISPLAY INVISIBLE (5930 10085);
FORCEADD GND..1
(4125 10275);
FORCEPROP 3 LASTPIN (4125 10325) SIG_NAME GND\g
J 0
(4135 10335);
DISPLAY 0.659574 (4135 10335);
PAINT MONO (4135 10335);
DISPLAY INVISIBLE (4135 10335);
FORCEPROP 1 LAST HDL_POWER GND
J 0
(4125 10425);
DISPLAY 0.872340 (4125 10425);
PAINT GREEN (4125 10425);
DISPLAY INVISIBLE (4125 10425);
FORCEPROP 2 LAST CDS_LIB logical_power
J 0
(4125 10275);
DISPLAY INVISIBLE (4125 10275);
FORCEPROP 1 LAST SIZE 1B
J 0
(4200 10225);
DISPLAY 0.872340 (4200 10225);
PAINT GREEN (4200 10225);
DISPLAY INVISIBLE (4200 10225);
FORCEPROP 1 LAST PATH I34
J 0
(4200 10275);
DISPLAY 0.872340 (4200 10275);
PAINT AQUA (4200 10275);
DISPLAY INVISIBLE (4200 10275);
FORCEADD GND..1
(4125 11550);
FORCEPROP 3 LASTPIN (4125 11600) SIG_NAME GND\g
J 0
(4135 11610);
DISPLAY 0.659574 (4135 11610);
PAINT MONO (4135 11610);
DISPLAY INVISIBLE (4135 11610);
FORCEPROP 1 LAST HDL_POWER GND
J 0
(4125 11700);
DISPLAY 0.872340 (4125 11700);
PAINT GREEN (4125 11700);
DISPLAY INVISIBLE (4125 11700);
FORCEPROP 1 LAST SIZE 1B
J 0
(4200 11500);
DISPLAY 0.872340 (4200 11500);
PAINT GREEN (4200 11500);
DISPLAY INVISIBLE (4200 11500);
FORCEPROP 2 LAST CDS_LIB logical_power
J 0
(4125 11550);
DISPLAY INVISIBLE (4125 11550);
FORCEPROP 1 LAST PATH I35
J 0
(4200 11550);
DISPLAY 0.872340 (4200 11550);
PAINT AQUA (4200 11550);
DISPLAY INVISIBLE (4200 11550);
FORCEADD MOSFET_NCH_DUAL..2
(4825 12275);
FORCEPROP 1 LAST PART_NUMBER BAM138K0003
J 0
(4976 12181);
DISPLAY 0.723404 (4976 12181);
PAINT GREEN (4976 12181);
DISPLAY INVISIBLE (4976 12181);
FORCEPROP 1 LAST MATERIAL IC
J 0
(4976 12126);
DISPLAY 0.723404 (4976 12126);
PAINT GREEN (4976 12126);
FORCEPROP 2 LAST VALUE PJT138K
J 0
(5000 12300);
DISPLAY 1.021277 (5000 12300);
FORCEPROP 2 LAST ROOM NIC1_P3V3_BOM1
J 0
(5000 12400);
DISPLAY 0.808511 (5000 12400);
FORCEPROP 2 LAST PART_TYPE SMLF
J 0
(5000 12350);
DISPLAY 1.021277 (5000 12350);
FORCEPROP 1 LAST LOCATION Q124
J 0
(4976 12251);
DISPLAY 0.723404 (4976 12251);
PAINT GREEN (4976 12251);
FORCEPROP 0 LASTPIN (4875 12475) $PN 3
R 1
J 0
(4865 12485);
DISPLAY 0.680851 (4865 12485);
PAINT MONO (4865 12485);
FORCEPROP 0 LASTPIN (4625 12225) $PN 5
J 2
(4615 12235);
DISPLAY 0.680851 (4615 12235);
PAINT MONO (4615 12235);
FORCEPROP 0 LASTPIN (4875 12075) $PN 4
R 1
J 2
(4865 12065);
DISPLAY 0.680851 (4865 12065);
PAINT MONO (4865 12065);
FORCEPROP 2 LAST CDS_LIB pure_quanta
J 0
(4825 12275);
DISPLAY INVISIBLE (4825 12275);
FORCEPROP 1 LAST CDS_LMAN_SYM_OUTLINE -150,150,150,-150
J 0
(4825 12275);
DISPLAY 0.468085 (4825 12275);
PAINT GREEN (4825 12275);
DISPLAY INVISIBLE (4825 12275);
FORCEPROP 1 LAST NEEDS_NO_SIZE TRUE
J 0
(4975 12166);
DISPLAY 0.468085 (4975 12166);
PAINT GREEN (4975 12166);
DISPLAY INVISIBLE (4975 12166);
FORCEPROP 1 LAST PATH I36
J 0
(4975 12125);
DISPLAY 0.723404 (4975 12125);
PAINT GREEN (4975 12125);
DISPLAY INVISIBLE (4975 12125);
FORCEPROP 0 LAST $SEC 2
J 0
(5000 12400);
DISPLAY 0.680851 (5000 12400);
PAINT MONO (5000 12400);
DISPLAY INVISIBLE (5000 12400);
FORCEPROP 0 LAST CDS_SEC 2
J 0
(5000 12400);
DISPLAY 1.021277 (5000 12400);
DISPLAY INVISIBLE (5000 12400);
FORCEADD GND..1
(4875 11925);
FORCEPROP 3 LASTPIN (4875 11975) SIG_NAME GND\g
J 0
(4885 11985);
DISPLAY 0.659574 (4885 11985);
PAINT MONO (4885 11985);
DISPLAY INVISIBLE (4885 11985);
FORCEPROP 1 LAST SIZE 1B
J 0
(4950 11875);
DISPLAY 0.872340 (4950 11875);
PAINT GREEN (4950 11875);
DISPLAY INVISIBLE (4950 11875);
FORCEPROP 1 LAST HDL_POWER GND
J 0
(4875 12075);
DISPLAY 0.872340 (4875 12075);
PAINT GREEN (4875 12075);
DISPLAY INVISIBLE (4875 12075);
FORCEPROP 2 LAST CDS_LIB logical_power
J 0
(4875 11925);
DISPLAY INVISIBLE (4875 11925);
FORCEPROP 1 LAST PATH I37
J 0
(4950 11925);
DISPLAY 0.872340 (4950 11925);
PAINT AQUA (4950 11925);
DISPLAY INVISIBLE (4950 11925);
FORCEADD DIODE_TVS..1
R 1
(5200 11425);
FORCEPROP 1 LAST PART_NUMBER BCSMF14AZ01
J 0
(5255 11342);
DISPLAY 0.510638 (5255 11342);
PAINT GREEN (5255 11342);
DISPLAY INVISIBLE (5255 11342);
FORCEPROP 2 LAST VALUE SMF14A
J 0
(5250 11400);
DISPLAY 0.510638 (5250 11400);
PAINT SKYBLUE (5250 11400);
FORCEPROP 1 LAST MATERIAL IC
J 0
(5250 11275);
DISPLAY 0.510638 (5250 11275);
PAINT GREEN (5250 11275);
FORCEPROP 1 LAST LOCATION PD101
J 0
(5255 11467);
DISPLAY 0.510638 (5255 11467);
PAINT GREEN (5255 11467);
FORCEPROP 0 LASTPIN (5200 11275) $PN A
R 1
J 2
(5190 11265);
DISPLAY 0.510638 (5190 11265);
FORCEPROP 0 LASTPIN (5200 11575) $PN C
R 1
J 0
(5190 11585);
DISPLAY 0.510638 (5190 11585);
FORCEPROP 1 LAST PIN_NAMES_ROTATE True
R 1
J 0
(5200 11425);
DISPLAY 0.489362 (5200 11425);
PAINT GREEN (5200 11425);
DISPLAY INVISIBLE (5200 11425);
FORCEPROP 0 LAST PART_TYPE SMLF
J 0
(5300 11550);
DISPLAY 1.021277 (5300 11550);
DISPLAY INVISIBLE (5300 11550);
FORCEPROP 1 LASTPIN (5200 11575) Pin_Length Short
R 1
J 0
(5210 11600);
DISPLAY 0.489362 (5210 11600);
PAINT MONO (5210 11600);
DISPLAY INVISIBLE (5210 11600);
FORCEPROP 1 LAST CDS_LMAN_SYM_OUTLINE -100,50,100,-50
R 1
J 0
(5200 11425);
DISPLAY 0.468085 (5200 11425);
PAINT GREEN (5200 11425);
DISPLAY INVISIBLE (5200 11425);
FORCEPROP 2 LAST CDS_LIB pure_quanta
J 0
(5200 11425);
DISPLAY INVISIBLE (5200 11425);
FORCEPROP 1 LAST PATH I38
R 1
J 0
(5250 11525);
DISPLAY 0.723404 (5250 11525);
PAINT GREEN (5250 11525);
DISPLAY INVISIBLE (5250 11525);
FORCEPROP 0 LAST $SEC 1
R 1
J 0
(5255 11517);
DISPLAY INVISIBLE (5255 11517);
FORCEPROP 0 LAST CDS_SEC 1
R 1
J 0
(5255 11517);
DISPLAY INVISIBLE (5255 11517);
FORCEADD Q_RES..1
(5400 10875);
FORCEPROP 1 LAST PART_NUMBER CS00002JB13
J 0
(5325 10825);
DISPLAY 0.510638 (5325 10825);
DISPLAY INVISIBLE (5325 10825);
FORCEPROP 1 LAST MATERIAL EMPTY
J 0
(5325 10800);
DISPLAY 0.510638 (5325 10800);
PAINT RED (5325 10800);
FORCEPROP 1 LAST WATTAGE 1/16W
J 2
(5600 10800);
DISPLAY 0.510638 (5600 10800);
FORCEPROP 1 LAST TOLERANCE 5%
J 0
(5575 10875);
DISPLAY 0.510638 (5575 10875);
FORCEPROP 1 LAST VALUE 0
J 2
(5550 10875);
DISPLAY 0.510638 (5550 10875);
FORCEPROP 1 LAST PACK_TYPE 0402LF
J 0
(5650 10875);
DISPLAY 0.510638 (5650 10875);
FORCEPROP 2 LAST ROOM NIC1_P12V_MAM_MAM_BOM1
J 0
(5175 10925);
DISPLAY 0.510638 (5175 10925);
FORCEPROP 1 LAST $LOCATION R3784
J 0
(5175 10875);
DISPLAY 0.510638 (5175 10875);
FORCEPROP 2 LAST CDS_LIB pure_quanta
J 0
(5400 10875);
DISPLAY INVISIBLE (5400 10875);
FORCEPROP 2 LAST ROOM1 NIC1_P12V_MAM_TIC_BOM2
J 0
(5175 10975);
DISPLAY 1.021277 (5175 10975);
DISPLAY INVISIBLE (5175 10975);
FORCEPROP 1 LAST PATH I39
J 0
(5350 11025);
DISPLAY 0.978723 (5350 11025);
PAINT WHITE (5350 11025);
DISPLAY INVISIBLE (5350 11025);
FORCEPROP 0 LAST CDS_LOCATION R3784
J 0
(5350 10975);
DISPLAY 1.021277 (5350 10975);
DISPLAY INVISIBLE (5350 10975);
FORCEPROP 0 LAST $SEC 1
J 0
(5350 10975);
DISPLAY 0.680851 (5350 10975);
PAINT MONO (5350 10975);
DISPLAY INVISIBLE (5350 10975);
FORCEPROP 0 LAST CDS_SEC 1
J 0
(5350 10975);
DISPLAY 1.021277 (5350 10975);
DISPLAY INVISIBLE (5350 10975);
FORCEPROP 1 LASTPIN (5300 10875) $PN 1
J 0
(5312 10887);
DISPLAY 0.787234 (5312 10887);
PAINT MONO (5312 10887);
DISPLAY INVISIBLE (5312 10887);
FORCEPROP 1 LASTPIN (5500 10875) $PN 2
J 0
(5462 10887);
DISPLAY 0.787234 (5462 10887);
PAINT MONO (5462 10887);
DISPLAY INVISIBLE (5462 10887);
FORCEADD Q_RES..1
(2425 10200);
FORCEPROP 1 LAST PART_NUMBER CS00002JB13
J 0
(2125 10125);
DISPLAY 0.510638 (2125 10125);
DISPLAY INVISIBLE (2125 10125);
FORCEPROP 1 LAST TOLERANCE 5%
J 0
(2600 10200);
DISPLAY 0.510638 (2600 10200);
FORCEPROP 1 LAST MATERIAL EMPTY
J 0
(2300 10075);
DISPLAY 0.510638 (2300 10075);
PAINT RED (2300 10075);
FORCEPROP 2 LAST ROOM NIC1_P12V_MAM_MAM_BOM1
J 0
(2600 10250);
DISPLAY 0.510638 (2600 10250);
FORCEPROP 1 LAST PACK_TYPE 0402LF
J 0
(2500 10125);
DISPLAY 0.510638 (2500 10125);
FORCEPROP 1 LAST WATTAGE 1/16W
J 2
(2625 10075);
DISPLAY 0.510638 (2625 10075);
FORCEPROP 1 LAST VALUE 0
J 2
(2575 10200);
DISPLAY 0.510638 (2575 10200);
FORCEPROP 1 LAST $LOCATION R4061
J 0
(2200 10200);
DISPLAY 0.510638 (2200 10200);
FORCEPROP 2 LAST ROOM1 NIC1_P12V_MAM_TIC_BOM2
J 0
(2600 10300);
DISPLAY 1.021277 (2600 10300);
DISPLAY INVISIBLE (2600 10300);
FORCEPROP 2 LAST CDS_LIB pure_quanta
J 0
(2425 10200);
DISPLAY INVISIBLE (2425 10200);
FORCEPROP 1 LAST PATH I4
J 0
(2375 10350);
DISPLAY 0.978723 (2375 10350);
PAINT WHITE (2375 10350);
DISPLAY INVISIBLE (2375 10350);
FORCEPROP 0 LAST CDS_LOCATION R4061
J 0
(2500 10275);
DISPLAY INVISIBLE (2500 10275);
FORCEPROP 0 LAST $SEC 1
J 0
(2500 10275);
DISPLAY INVISIBLE (2500 10275);
FORCEPROP 0 LAST CDS_SEC 1
J 0
(2500 10275);
DISPLAY INVISIBLE (2500 10275);
FORCEPROP 1 LASTPIN (2325 10200) $PN 1
J 0
(2337 10212);
DISPLAY 0.787234 (2337 10212);
PAINT MONO (2337 10212);
DISPLAY INVISIBLE (2337 10212);
FORCEPROP 1 LASTPIN (2525 10200) $PN 2
J 0
(2487 10212);
DISPLAY 0.787234 (2487 10212);
PAINT MONO (2487 10212);
DISPLAY INVISIBLE (2487 10212);
FORCEADD GND..1
(5350 11050);
FORCEPROP 3 LASTPIN (5350 11100) SIG_NAME GND\g
J 0
(5360 11110);
DISPLAY 0.659574 (5360 11110);
PAINT MONO (5360 11110);
DISPLAY INVISIBLE (5360 11110);
FORCEPROP 1 LAST HDL_POWER GND
J 0
(5350 11200);
DISPLAY 0.872340 (5350 11200);
PAINT GREEN (5350 11200);
DISPLAY INVISIBLE (5350 11200);
FORCEPROP 2 LAST CDS_LIB logical_power
J 0
(5350 11050);
DISPLAY INVISIBLE (5350 11050);
FORCEPROP 1 LAST SIZE 1B
J 0
(5425 11000);
DISPLAY 0.872340 (5425 11000);
PAINT GREEN (5425 11000);
DISPLAY INVISIBLE (5425 11000);
FORCEPROP 1 LAST PATH I40
J 0
(5425 11050);
DISPLAY 0.872340 (5425 11050);
PAINT AQUA (5425 11050);
DISPLAY INVISIBLE (5425 11050);
FORCEADD Q_RES..2
(5925 10450);
FORCEPROP 1 LAST PART_NUMBER CS26802FB02
J 0
(5975 10400);
DISPLAY 0.510638 (5975 10400);
DISPLAY INVISIBLE (5975 10400);
FORCEPROP 2 LAST ROOM NIC1_P12V_MAM_MAM_BOM1
J 0
(5975 10550);
DISPLAY 0.510638 (5975 10550);
FORCEPROP 1 LAST WATTAGE 1/16W
J 0
(5975 10450);
DISPLAY 0.510638 (5975 10450);
FORCEPROP 1 LAST TOLERANCE 1%
J 0
(5975 10475);
DISPLAY 0.510638 (5975 10475);
FORCEPROP 1 LAST VALUE 6.8K
J 0
(5975 10500);
DISPLAY 0.510638 (5975 10500);
FORCEPROP 1 LAST MATERIAL EMPTY
J 0
(5975 10425);
DISPLAY 0.510638 (5975 10425);
PAINT RED (5975 10425);
FORCEPROP 1 LAST PACK_TYPE 0402LF
J 0
(5975 10375);
DISPLAY 0.510638 (5975 10375);
FORCEPROP 1 LAST LOCATION PR3787
J 0
(5975 10525);
DISPLAY 0.510638 (5975 10525);
FORCEPROP 2 LAST ROOM1 NIC1_P12V_MAM_TIC_BOM2
J 0
(5975 10625);
DISPLAY 1.021277 (5975 10625);
DISPLAY INVISIBLE (5975 10625);
FORCEPROP 2 LAST CDS_LIB pure_quanta
J 0
(5925 10450);
DISPLAY INVISIBLE (5925 10450);
FORCEPROP 1 LAST PATH I41
J 0
(5975 10625);
DISPLAY 0.978723 (5975 10625);
PAINT WHITE (5975 10625);
DISPLAY INVISIBLE (5975 10625);
FORCEPROP 0 LAST $SEC 1
J 0
(5975 10575);
DISPLAY 0.680851 (5975 10575);
PAINT MONO (5975 10575);
DISPLAY INVISIBLE (5975 10575);
FORCEPROP 0 LAST CDS_SEC 1
J 0
(5975 10575);
DISPLAY 1.021277 (5975 10575);
DISPLAY INVISIBLE (5975 10575);
FORCEPROP 1 LASTPIN (5925 10550) $PN 1
J 0
(5930 10512);
DISPLAY 0.787234 (5930 10512);
PAINT MONO (5930 10512);
DISPLAY INVISIBLE (5930 10512);
FORCEPROP 1 LASTPIN (5925 10350) $PN 2
J 0
(5930 10360);
DISPLAY 0.787234 (5930 10360);
PAINT MONO (5930 10360);
DISPLAY INVISIBLE (5930 10360);
FORCEADD Q_RES..2
(5925 11125);
FORCEPROP 1 LAST PART_NUMBER CS41602FB05
J 0
(5975 11075);
DISPLAY 0.510638 (5975 11075);
DISPLAY INVISIBLE (5975 11075);
FORCEPROP 1 LAST MATERIAL EMPTY
J 0
(5975 11100);
DISPLAY 0.510638 (5975 11100);
PAINT RED (5975 11100);
FORCEPROP 1 LAST PACK_TYPE 0402LF
J 0
(5975 11050);
DISPLAY 0.510638 (5975 11050);
FORCEPROP 1 LAST WATTAGE 1/16W
J 0
(5975 11125);
DISPLAY 0.510638 (5975 11125);
FORCEPROP 1 LAST TOLERANCE 1%
J 0
(5975 11150);
DISPLAY 0.510638 (5975 11150);
FORCEPROP 1 LAST VALUE 160K
J 0
(5975 11175);
DISPLAY 0.510638 (5975 11175);
FORCEPROP 2 LAST ROOM NIC1_P12V_MAM_MAM_BOM1
J 0
(5975 11250);
DISPLAY 0.510638 (5975 11250);
FORCEPROP 1 LAST LOCATION PR3786
J 0
(5975 11200);
DISPLAY 0.510638 (5975 11200);
FORCEPROP 2 LAST ROOM1 NIC1_P12V_MAM_TIC_BOM2
J 0
(5975 11300);
DISPLAY 1.021277 (5975 11300);
DISPLAY INVISIBLE (5975 11300);
FORCEPROP 2 LAST CDS_LIB pure_quanta
J 0
(5925 11125);
DISPLAY INVISIBLE (5925 11125);
FORCEPROP 1 LAST PATH I42
J 0
(5975 11300);
DISPLAY 0.978723 (5975 11300);
PAINT WHITE (5975 11300);
DISPLAY INVISIBLE (5975 11300);
FORCEPROP 0 LAST $SEC 1
J 0
(5975 11250);
DISPLAY 0.680851 (5975 11250);
PAINT MONO (5975 11250);
DISPLAY INVISIBLE (5975 11250);
FORCEPROP 0 LAST CDS_SEC 1
J 0
(5975 11250);
DISPLAY 1.021277 (5975 11250);
DISPLAY INVISIBLE (5975 11250);
FORCEPROP 1 LASTPIN (5925 11225) $PN 1
J 0
(5930 11187);
DISPLAY 0.787234 (5930 11187);
PAINT MONO (5930 11187);
DISPLAY INVISIBLE (5930 11187);
FORCEPROP 1 LASTPIN (5925 11025) $PN 2
J 0
(5930 11035);
DISPLAY 0.787234 (5930 11035);
PAINT MONO (5930 11035);
DISPLAY INVISIBLE (5930 11035);
FORCEADD UNIVERSAL_POWER..1
(5350 11775);
FORCEPROP 3 LASTPIN (5350 11725) SIG_NAME P12V_AUX\g
J 0
(5360 11735);
DISPLAY 0.659574 (5360 11735);
PAINT MONO (5360 11735);
DISPLAY INVISIBLE (5360 11735);
FORCEPROP 1 LAST HDL_POWER P12V_AUX
J 1
(5350 11825);
DISPLAY 0.510638 (5350 11825);
PAINT GREEN (5350 11825);
FORCEPROP 2 LAST CDS_LIB logical_power
J 0
(5350 11775);
DISPLAY INVISIBLE (5350 11775);
FORCEPROP 1 LAST PATH I43
J 0
(5400 11800);
DISPLAY 0.872340 (5400 11800);
PAINT AQUA (5400 11800);
DISPLAY INVISIBLE (5400 11800);
FORCEADD Q_CAP..1
(5575 11425);
FORCEPROP 1 LAST PART_NUMBER CH5104KEB02
J 0
(5625 11375);
DISPLAY 0.510638 (5625 11375);
DISPLAY INVISIBLE (5625 11375);
FORCEPROP 1 LAST VOLTAGE 25V
J 0
(5625 11450);
DISPLAY 0.510638 (5625 11450);
FORCEPROP 1 LAST PACK_TYPE C0402
J 0
(5625 11400);
DISPLAY 0.510638 (5625 11400);
FORCEPROP 1 LAST MATERIAL X6S
J 0
(5625 11425);
DISPLAY 0.510638 (5625 11425);
FORCEPROP 1 LAST VALUE 1UF
J 0
(5625 11475);
DISPLAY 0.510638 (5625 11475);
FORCEPROP 1 LAST LOCATION PC2079
J 0
(5625 11500);
DISPLAY 0.510638 (5625 11500);
FORCEPROP 1 LAST TOLERANCE 10%
J 0
(5625 11375);
DISPLAY 0.638298 (5625 11375);
DISPLAY INVISIBLE (5625 11375);
FORCEPROP 2 LAST CDS_LIB pure_quanta
J 0
(5575 11425);
DISPLAY INVISIBLE (5575 11425);
FORCEPROP 1 LAST PATH I44
J 0
(5625 11575);
DISPLAY 0.978723 (5625 11575);
PAINT WHITE (5625 11575);
DISPLAY INVISIBLE (5625 11575);
FORCEPROP 0 LAST $SEC 1
J 0
(5630 11567);
DISPLAY INVISIBLE (5630 11567);
FORCEPROP 0 LAST CDS_SEC 1
J 0
(5630 11567);
DISPLAY INVISIBLE (5630 11567);
FORCEPROP 1 LASTPIN (5575 11525) $PN 1
J 0
(5585 11505);
DISPLAY 0.787234 (5585 11505);
PAINT MONO (5585 11505);
DISPLAY INVISIBLE (5585 11505);
FORCEPROP 1 LASTPIN (5575 11325) $PN 2
J 0
(5585 11305);
DISPLAY 0.787234 (5585 11305);
PAINT MONO (5585 11305);
DISPLAY INVISIBLE (5585 11305);
FORCEADD Q_RES..1
(6750 8725);
FORCEPROP 1 LAST PART_NUMBER CS00002JB13
J 0
(6675 8675);
DISPLAY 0.404255 (6675 8675);
DISPLAY INVISIBLE (6675 8675);
FORCEPROP 1 LAST WATTAGE 1/16W
J 2
(6875 8650);
DISPLAY 0.404255 (6875 8650);
FORCEPROP 1 LAST MATERIAL CHIP
J 0
(6675 8650);
DISPLAY 0.404255 (6675 8650);
FORCEPROP 1 LAST VALUE 0
J 2
(6900 8725);
DISPLAY 0.404255 (6900 8725);
FORCEPROP 1 LAST PACK_TYPE 0402LF
J 0
(6975 8725);
DISPLAY 0.404255 (6975 8725);
FORCEPROP 1 LAST TOLERANCE 5%
J 0
(6925 8725);
DISPLAY 0.404255 (6925 8725);
FORCEPROP 1 LAST $LOCATION R4752
J 0
(6550 8725);
DISPLAY 0.638298 (6550 8725);
FORCEPROP 1 LASTPIN (6650 8725) $PN 1
J 0
(6662 8737);
DISPLAY 0.787234 (6662 8737);
FORCEPROP 1 LASTPIN (6850 8725) $PN 2
J 0
(6812 8737);
DISPLAY 0.787234 (6812 8737);
FORCEPROP 2 LAST CDS_LIB pure_quanta
J 0
(6750 8725);
PAINT MONO (6750 8725);
DISPLAY INVISIBLE (6750 8725);
FORCEPROP 1 LAST PATH I45
J 0
(6700 8875);
DISPLAY 0.978723 (6700 8875);
PAINT WHITE (6700 8875);
DISPLAY INVISIBLE (6700 8875);
FORCEPROP 2 LAST CDS_LOCATION R4752
J 0
(6700 8925);
DISPLAY 1.021277 (6700 8925);
DISPLAY INVISIBLE (6700 8925);
FORCEPROP 2 LAST $SEC 1
J 0
(6700 8925);
DISPLAY 0.680851 (6700 8925);
PAINT MONO (6700 8925);
DISPLAY INVISIBLE (6700 8925);
FORCEPROP 2 LAST CDS_SEC 1
J 0
(6700 8925);
DISPLAY 1.021277 (6700 8925);
DISPLAY INVISIBLE (6700 8925);
FORCEADD Q_RES..1
(6750 8875);
FORCEPROP 1 LAST PART_NUMBER CS00002JB13
J 0
(6675 8825);
DISPLAY 0.510638 (6675 8825);
DISPLAY INVISIBLE (6675 8825);
FORCEPROP 1 LAST MATERIAL CHIP
J 0
(6675 8800);
DISPLAY 0.510638 (6675 8800);
FORCEPROP 1 LAST TOLERANCE 5%
J 0
(6925 8875);
DISPLAY 0.510638 (6925 8875);
FORCEPROP 1 LAST VALUE 0
J 2
(6900 8875);
DISPLAY 0.510638 (6900 8875);
FORCEPROP 1 LAST WATTAGE 1/16W
J 2
(6875 8800);
DISPLAY 0.510638 (6875 8800);
FORCEPROP 1 LAST PACK_TYPE 0402LF
J 0
(6975 8875);
DISPLAY 0.510638 (6975 8875);
FORCEPROP 1 LAST $LOCATION R1148
J 0
(6550 8875);
DISPLAY 0.510638 (6550 8875);
FORCEPROP 1 LASTPIN (6650 8875) $PN 1
J 0
(6662 8887);
DISPLAY 0.510638 (6662 8887);
FORCEPROP 1 LASTPIN (6850 8875) $PN 2
J 0
(6812 8887);
DISPLAY 0.510638 (6812 8887);
FORCEPROP 2 LAST CDS_LIB pure_quanta
J 0
(6750 8875);
PAINT MONO (6750 8875);
DISPLAY INVISIBLE (6750 8875);
FORCEPROP 1 LAST PATH I46
J 0
(6700 9025);
DISPLAY 0.978723 (6700 9025);
PAINT WHITE (6700 9025);
DISPLAY INVISIBLE (6700 9025);
FORCEPROP 2 LAST CDS_LOCATION R1148
J 0
(6700 9075);
DISPLAY 1.021277 (6700 9075);
DISPLAY INVISIBLE (6700 9075);
FORCEPROP 2 LAST $SEC 1
J 0
(6700 9075);
DISPLAY 0.680851 (6700 9075);
PAINT MONO (6700 9075);
DISPLAY INVISIBLE (6700 9075);
FORCEPROP 2 LAST CDS_SEC 1
J 0
(6700 9075);
DISPLAY 1.021277 (6700 9075);
DISPLAY INVISIBLE (6700 9075);
FORCEADD Q_RES..1
(6775 9025);
FORCEPROP 1 LAST PART_NUMBER CS00002JB13
J 0
(6700 8975);
DISPLAY 0.510638 (6700 8975);
DISPLAY INVISIBLE (6700 8975);
FORCEPROP 1 LAST PACK_TYPE 0402LF
J 0
(7000 9025);
DISPLAY 0.510638 (7000 9025);
FORCEPROP 1 LAST TOLERANCE 5%
J 0
(6950 9025);
DISPLAY 0.510638 (6950 9025);
FORCEPROP 1 LAST VALUE 0
J 2
(6925 9025);
DISPLAY 0.510638 (6925 9025);
FORCEPROP 1 LAST MATERIAL CHIP
J 0
(6700 8950);
DISPLAY 0.510638 (6700 8950);
FORCEPROP 1 LAST WATTAGE 1/16W
J 2
(6900 8950);
DISPLAY 0.510638 (6900 8950);
FORCEPROP 1 LAST $LOCATION R1147
J 0
(6575 9025);
DISPLAY 0.510638 (6575 9025);
FORCEPROP 1 LASTPIN (6675 9025) $PN 1
J 0
(6687 9037);
DISPLAY 0.510638 (6687 9037);
FORCEPROP 1 LASTPIN (6875 9025) $PN 2
J 0
(6837 9037);
DISPLAY 0.510638 (6837 9037);
FORCEPROP 2 LAST CDS_LIB pure_quanta
J 0
(6775 9025);
PAINT MONO (6775 9025);
DISPLAY INVISIBLE (6775 9025);
FORCEPROP 1 LAST PATH I47
J 0
(6725 9175);
DISPLAY 0.978723 (6725 9175);
PAINT WHITE (6725 9175);
DISPLAY INVISIBLE (6725 9175);
FORCEPROP 2 LAST CDS_LOCATION R1147
J 0
(6725 9225);
DISPLAY 1.021277 (6725 9225);
DISPLAY INVISIBLE (6725 9225);
FORCEPROP 2 LAST $SEC 1
J 0
(6725 9225);
DISPLAY 0.680851 (6725 9225);
PAINT MONO (6725 9225);
DISPLAY INVISIBLE (6725 9225);
FORCEPROP 2 LAST CDS_SEC 1
J 0
(6725 9225);
DISPLAY 1.021277 (6725 9225);
DISPLAY INVISIBLE (6725 9225);
FORCEADD GND..1
(6775 9900);
FORCEPROP 3 LASTPIN (6775 9950) SIG_NAME GND\g
J 0
(6785 9960);
DISPLAY 0.659574 (6785 9960);
PAINT MONO (6785 9960);
DISPLAY INVISIBLE (6785 9960);
FORCEPROP 1 LAST HDL_POWER GND
J 0
(6775 10050);
DISPLAY 0.872340 (6775 10050);
PAINT GREEN (6775 10050);
DISPLAY INVISIBLE (6775 10050);
FORCEPROP 1 LAST SIZE 1B
J 0
(6850 9850);
DISPLAY 0.872340 (6850 9850);
PAINT GREEN (6850 9850);
DISPLAY INVISIBLE (6850 9850);
FORCEPROP 2 LAST CDS_LIB logical_power
J 0
(6775 9900);
DISPLAY INVISIBLE (6775 9900);
FORCEPROP 1 LAST PATH I48
J 0
(6850 9900);
DISPLAY 0.872340 (6850 9900);
PAINT AQUA (6850 9900);
DISPLAY INVISIBLE (6850 9900);
FORCEADD Q_RES..2
(6775 10200);
FORCEPROP 1 LAST PART_NUMBER CS33012FB03
J 0
(6825 10125);
DISPLAY 0.510638 (6825 10125);
DISPLAY INVISIBLE (6825 10125);
FORCEPROP 2 LAST ROOM NIC1_P12V_MAM_MAM_BOM1
J 0
(6825 10300);
DISPLAY 0.510638 (6825 10300);
FORCEPROP 1 LAST VALUE 30.1K
J 0
(6825 10225);
DISPLAY 0.510638 (6825 10225);
FORCEPROP 1 LAST WATTAGE 1/16W
J 0
(6825 10175);
DISPLAY 0.510638 (6825 10175);
FORCEPROP 1 LAST MATERIAL EMPTY
J 0
(6825 10150);
DISPLAY 0.510638 (6825 10150);
PAINT RED (6825 10150);
FORCEPROP 1 LAST PACK_TYPE 0402LF
J 0
(6825 10100);
DISPLAY 0.510638 (6825 10100);
FORCEPROP 1 LAST TOLERANCE 1%
J 0
(6825 10200);
DISPLAY 0.510638 (6825 10200);
FORCEPROP 1 LAST $LOCATION PR5484
J 0
(6825 10250);
DISPLAY 0.510638 (6825 10250);
FORCEPROP 1 LASTPIN (6775 10300) $PN 1
J 0
(6780 10262);
DISPLAY 0.510638 (6780 10262);
PAINT MONO (6780 10262);
FORCEPROP 1 LASTPIN (6775 10100) $PN 2
J 0
(6780 10110);
DISPLAY 0.510638 (6780 10110);
PAINT MONO (6780 10110);
FORCEPROP 2 LAST ROOM1 NIC1_P12V_MAM_TIC_BOM2
J 0
(6825 10350);
DISPLAY 1.021277 (6825 10350);
DISPLAY INVISIBLE (6825 10350);
FORCEPROP 2 LAST CDS_LIB pure_quanta
J 0
(6775 10200);
DISPLAY INVISIBLE (6775 10200);
FORCEPROP 1 LAST PATH I49
J 0
(6825 10375);
DISPLAY 0.978723 (6825 10375);
PAINT WHITE (6825 10375);
DISPLAY INVISIBLE (6825 10375);
FORCEPROP 0 LAST CDS_LOCATION PR5484
J 0
(6825 10300);
DISPLAY 1.021277 (6825 10300);
DISPLAY INVISIBLE (6825 10300);
FORCEPROP 0 LAST $SEC 1
J 0
(6825 10350);
DISPLAY 0.680851 (6825 10350);
PAINT MONO (6825 10350);
DISPLAY INVISIBLE (6825 10350);
FORCEPROP 0 LAST CDS_SEC 1
J 0
(6825 10325);
DISPLAY INVISIBLE (6825 10325);
FORCEADD OFFPAGE..1
(3625 8475);
FORCEPROP 2 LAST $XR1 165 
J 0
(3253 8475);
DISPLAY 0.638298 (3253 8475);
PAINT MONO (3253 8475);
FORCEPROP 2 LAST $XR0 153 
J 0
(3373 8475);
DISPLAY 0.638298 (3373 8475);
PAINT MONO (3373 8475);
FORCEPROP 1 LAST COMMENT_BODY TRUE
J 0
(3750 8375);
DISPLAY 0.872340 (3750 8375);
PAINT GREEN (3750 8375);
DISPLAY INVISIBLE (3750 8375);
FORCEPROP 1 LAST OFFPAGE TRUE
J 0
(3950 8350);
DISPLAY 0.872340 (3950 8350);
PAINT GREEN (3950 8350);
DISPLAY INVISIBLE (3950 8350);
FORCEPROP 2 LAST CDS_LIB standard
J 0
(3625 8475);
PAINT MONO (3625 8475);
DISPLAY INVISIBLE (3625 8475);
FORCEPROP 2 LAST PATH I5
J 0
(3375 8500);
DISPLAY 1.021277 (3375 8500);
DISPLAY INVISIBLE (3375 8500);
FORCEADD Q_RES..2
(8025 9300);
FORCEPROP 1 LAST PART_NUMBER CS31002FB08
J 0
(8065 9175);
DISPLAY 0.510638 (8065 9175);
DISPLAY INVISIBLE (8065 9175);
FORCEPROP 1 LAST WATTAGE 1/16W
J 0
(8065 9275);
DISPLAY 0.510638 (8065 9275);
FORCEPROP 1 LAST TOLERANCE 1%
J 0
(8070 9325);
DISPLAY 0.510638 (8070 9325);
FORCEPROP 1 LAST VALUE 10K
J 0
(8070 9375);
DISPLAY 0.510638 (8070 9375);
FORCEPROP 1 LAST MATERIAL CHIP
J 0
(8065 9225);
DISPLAY 0.510638 (8065 9225);
FORCEPROP 1 LAST PACK_TYPE 0402LF
J 0
(8065 9175);
DISPLAY 0.510638 (8065 9175);
FORCEPROP 1 LAST $LOCATION R1149
J 0
(8070 9425);
DISPLAY 0.510638 (8070 9425);
FORCEPROP 1 LASTPIN (8025 9400) $PN 1
J 0
(8030 9362);
DISPLAY 0.510638 (8030 9362);
FORCEPROP 1 LASTPIN (8025 9200) $PN 2
J 0
(8030 9210);
DISPLAY 0.510638 (8030 9210);
FORCEPROP 2 LAST CDS_LIB pure_quanta
J 0
(8025 9300);
PAINT MONO (8025 9300);
DISPLAY INVISIBLE (8025 9300);
FORCEPROP 1 LAST PATH I50
J 0
(8075 9475);
DISPLAY 0.978723 (8075 9475);
PAINT WHITE (8075 9475);
DISPLAY INVISIBLE (8075 9475);
FORCEPROP 2 LAST CDS_LOCATION R1149
J 0
(8075 9525);
DISPLAY 1.021277 (8075 9525);
DISPLAY INVISIBLE (8075 9525);
FORCEPROP 2 LAST $SEC 1
J 0
(8075 9525);
DISPLAY 0.680851 (8075 9525);
PAINT MONO (8075 9525);
DISPLAY INVISIBLE (8075 9525);
FORCEPROP 2 LAST CDS_SEC 1
J 0
(8075 9525);
DISPLAY 1.021277 (8075 9525);
DISPLAY INVISIBLE (8075 9525);
FORCEADD MAX15090BEWIT..1
(7525 10700);
FORCEPROP 1 LAST PART_NUMBER AL015080B00
J 0
(7272 11344);
DISPLAY 0.510638 (7272 11344);
PAINT GREEN (7272 11344);
DISPLAY INVISIBLE (7272 11344);
FORCEPROP 2 LAST ROOM NIC1_P12V_MAM_MAM_BOM1
J 0
(7275 11575);
DISPLAY 0.510638 (7275 11575);
FORCEPROP 2 LAST VALUE MAX15090BEWI+T
J 0
(7275 11475);
DISPLAY 0.510638 (7275 11475);
FORCEPROP 2 LAST PART_TYPE SMLF
J 0
(7275 11525);
DISPLAY 0.510638 (7275 11525);
FORCEPROP 1 LAST MATERIAL EMPTY
J 0
(7272 11255);
DISPLAY 0.510638 (7272 11255);
PAINT RED (7272 11255);
FORCEPROP 1 LAST LOCATION PU203
J 0
(7272 11428);
DISPLAY 0.510638 (7272 11428);
PAINT GREEN (7272 11428);
FORCEPROP 0 LASTPIN (7125 10400) $PN B1
J 2
(7115 10410);
DISPLAY 0.510638 (7115 10410);
PAINT MONO (7115 10410);
FORCEPROP 0 LASTPIN (7925 10400) $PN A7
J 0
(7935 10410);
DISPLAY 0.510638 (7935 10410);
PAINT MONO (7935 10410);
FORCEPROP 0 LASTPIN (7125 10300) $PN B7
J 2
(7115 10310);
DISPLAY 0.510638 (7115 10310);
PAINT MONO (7115 10310);
FORCEPROP 0 LASTPIN (7925 10600) $PN C7
J 0
(7935 10610);
DISPLAY 0.510638 (7935 10610);
PAINT MONO (7935 10610);
FORCEPROP 0 LASTPIN (7925 10800) $PN A6
J 0
(7935 10810);
DISPLAY 0.510638 (7935 10810);
PAINT MONO (7935 10810);
FORCEPROP 0 LASTPIN (7925 10300) $PN B2
J 0
(7935 10310);
DISPLAY 0.510638 (7935 10310);
PAINT MONO (7935 10310);
FORCEPROP 0 LASTPIN (7925 10250) $PN C1
J 0
(7935 10260);
DISPLAY 0.510638 (7935 10260);
PAINT MONO (7935 10260);
FORCEPROP 0 LASTPIN (7925 10200) $PN C2
J 0
(7935 10210);
DISPLAY 0.510638 (7935 10210);
PAINT MONO (7935 10210);
FORCEPROP 0 LASTPIN (7125 11200) $PN A3
J 2
(7115 11210);
DISPLAY 0.510638 (7115 11210);
PAINT MONO (7115 11210);
FORCEPROP 0 LASTPIN (7125 11150) $PN A5
J 2
(7115 11160);
DISPLAY 0.510638 (7115 11160);
PAINT MONO (7115 11160);
FORCEPROP 0 LASTPIN (7125 11100) $PN B3
J 2
(7115 11110);
DISPLAY 0.510638 (7115 11110);
PAINT MONO (7115 11110);
FORCEPROP 0 LASTPIN (7125 11050) $PN B5
J 2
(7115 11060);
DISPLAY 0.510638 (7115 11060);
PAINT MONO (7115 11060);
FORCEPROP 0 LASTPIN (7125 11000) $PN C3
J 2
(7115 11010);
DISPLAY 0.510638 (7115 11010);
PAINT MONO (7115 11010);
FORCEPROP 0 LASTPIN (7125 10950) $PN C5
J 2
(7115 10960);
DISPLAY 0.510638 (7115 10960);
PAINT MONO (7115 10960);
FORCEPROP 0 LASTPIN (7125 10900) $PN D5
J 2
(7115 10910);
DISPLAY 0.510638 (7115 10910);
PAINT MONO (7115 10910);
FORCEPROP 0 LASTPIN (7925 10500) $PN A1
J 0
(7935 10510);
DISPLAY 0.510638 (7935 10510);
PAINT MONO (7935 10510);
FORCEPROP 0 LASTPIN (7925 11200) $PN A4
J 0
(7935 11210);
DISPLAY 0.510638 (7935 11210);
PAINT MONO (7935 11210);
FORCEPROP 0 LASTPIN (7925 11150) $PN B4
J 0
(7935 11160);
DISPLAY 0.510638 (7935 11160);
PAINT MONO (7935 11160);
FORCEPROP 0 LASTPIN (7925 11100) $PN B6
J 0
(7935 11110);
DISPLAY 0.510638 (7935 11110);
PAINT MONO (7935 11110);
FORCEPROP 0 LASTPIN (7925 11050) $PN C4
J 0
(7935 11060);
DISPLAY 0.510638 (7935 11060);
PAINT MONO (7935 11060);
FORCEPROP 0 LASTPIN (7925 11000) $PN C6
J 0
(7935 11010);
DISPLAY 0.510638 (7935 11010);
PAINT MONO (7935 11010);
FORCEPROP 0 LASTPIN (7925 10950) $PN D4
J 0
(7935 10960);
DISPLAY 0.510638 (7935 10960);
PAINT MONO (7935 10960);
FORCEPROP 0 LASTPIN (7925 10900) $PN D6
J 0
(7935 10910);
DISPLAY 0.510638 (7935 10910);
PAINT MONO (7935 10910);
FORCEPROP 0 LASTPIN (7125 10500) $PN D3
J 2
(7115 10510);
DISPLAY 0.510638 (7115 10510);
PAINT MONO (7115 10510);
FORCEPROP 0 LASTPIN (7925 10700) $PN D7
J 0
(7935 10710);
DISPLAY 0.510638 (7935 10710);
PAINT MONO (7935 10710);
FORCEPROP 0 LASTPIN (7125 10700) $PN D1
J 2
(7115 10710);
DISPLAY 0.510638 (7115 10710);
PAINT MONO (7115 10710);
FORCEPROP 0 LASTPIN (7125 10600) $PN D2
J 2
(7115 10610);
DISPLAY 0.510638 (7115 10610);
PAINT MONO (7115 10610);
FORCEPROP 0 LASTPIN (7125 10800) $PN A2
J 2
(7115 10810);
DISPLAY 0.510638 (7115 10810);
PAINT MONO (7115 10810);
FORCEPROP 2 LAST ROOM1 NIC1_P12V_MAM_TIC_BOM2
J 0
(7275 11625);
DISPLAY 1.021277 (7275 11625);
DISPLAY INVISIBLE (7275 11625);
FORCEPROP 2 LAST CDS_LIB pure_quanta
J 0
(7525 10700);
DISPLAY INVISIBLE (7525 10700);
FORCEPROP 1 LAST PIN_NAMES_ROTATE True
J 0
(7525 10700);
DISPLAY 0.489362 (7525 10700);
PAINT GREEN (7525 10700);
DISPLAY INVISIBLE (7525 10700);
FORCEPROP 1 LAST CDS_LMAN_SYM_OUTLINE -250,550,250,-550
J 0
(7525 10700);
DISPLAY 0.468085 (7525 10700);
PAINT GREEN (7525 10700);
DISPLAY INVISIBLE (7525 10700);
FORCEPROP 1 LAST PATH I51
J 0
(7775 10150);
DISPLAY 0.723404 (7775 10150);
PAINT GREEN (7775 10150);
DISPLAY INVISIBLE (7775 10150);
FORCEPROP 0 LAST $SEC 1
J 0
(7275 11575);
DISPLAY 0.680851 (7275 11575);
PAINT MONO (7275 11575);
DISPLAY INVISIBLE (7275 11575);
FORCEPROP 0 LAST CDS_SEC 1
J 0
(7275 11575);
DISPLAY 1.021277 (7275 11575);
DISPLAY INVISIBLE (7275 11575);
FORCEADD UNIVERSAL_POWER..1
(8025 9600);
FORCEPROP 3 LASTPIN (8025 9550) SIG_NAME P3V3_AUX\g
J 0
(8035 9560);
DISPLAY 0.659574 (8035 9560);
PAINT MONO (8035 9560);
DISPLAY INVISIBLE (8035 9560);
FORCEPROP 1 LAST HDL_POWER P3V3_AUX
J 1
(8025 9650);
DISPLAY 0.510638 (8025 9650);
PAINT GREEN (8025 9650);
FORCEPROP 2 LAST CDS_LIB logical_power
J 0
(8025 9600);
PAINT MONO (8025 9600);
DISPLAY INVISIBLE (8025 9600);
FORCEPROP 1 LAST PATH I52
J 0
(8075 9625);
DISPLAY 0.872340 (8075 9625);
PAINT AQUA (8075 9625);
DISPLAY INVISIBLE (8075 9625);
FORCEADD GND..1
(6250 10625);
FORCEPROP 3 LASTPIN (6250 10675) SIG_NAME GND\g
J 0
(6260 10685);
DISPLAY 0.659574 (6260 10685);
PAINT MONO (6260 10685);
DISPLAY INVISIBLE (6260 10685);
FORCEPROP 1 LAST HDL_POWER GND
J 0
(6250 10775);
DISPLAY 0.872340 (6250 10775);
PAINT GREEN (6250 10775);
DISPLAY INVISIBLE (6250 10775);
FORCEPROP 2 LAST CDS_LIB logical_power
J 0
(6250 10625);
DISPLAY INVISIBLE (6250 10625);
FORCEPROP 1 LAST SIZE 1B
J 0
(6325 10575);
DISPLAY 0.872340 (6325 10575);
PAINT GREEN (6325 10575);
DISPLAY INVISIBLE (6325 10575);
FORCEPROP 1 LAST PATH I53
J 0
(6325 10625);
DISPLAY 0.872340 (6325 10625);
PAINT AQUA (6325 10625);
DISPLAY INVISIBLE (6325 10625);
FORCEADD Q_CAP..1
R 1
(6475 10700);
FORCEPROP 1 LAST PART_NUMBER CH5104KEB02
J 0
(6525 10650);
DISPLAY 0.510638 (6525 10650);
DISPLAY INVISIBLE (6525 10650);
FORCEPROP 2 LAST ROOM NIC1_P12V_MAM_MAM_BOM1
J 0
(6300 10775);
DISPLAY 0.510638 (6300 10775);
FORCEPROP 1 LAST PACK_TYPE C0402
J 0
(6300 10650);
DISPLAY 0.510638 (6300 10650);
FORCEPROP 1 LAST VOLTAGE 25V
J 0
(6625 10750);
DISPLAY 0.510638 (6625 10750);
FORCEPROP 1 LAST VALUE 1UF
J 0
(6450 10750);
DISPLAY 0.510638 (6450 10750);
FORCEPROP 1 LAST LOCATION PC2087
J 0
(6300 10750);
DISPLAY 0.510638 (6300 10750);
FORCEPROP 2 LAST ROOM1 NIC1_P12V_MAM_TIC_BOM2
J 0
(6300 10850);
DISPLAY 1.021277 (6300 10850);
DISPLAY INVISIBLE (6300 10850);
FORCEPROP 2 LAST CDS_LIB pure_quanta
J 0
(6475 10700);
DISPLAY INVISIBLE (6475 10700);
FORCEPROP 1 LAST TOLERANCE 10%
R 1
J 0
(6525 10750);
DISPLAY 0.638298 (6525 10750);
DISPLAY INVISIBLE (6525 10750);
FORCEPROP 1 LAST MATERIAL EMPTY
R 1
J 0
(6475 10750);
DISPLAY 0.638298 (6475 10750);
DISPLAY INVISIBLE (6475 10750);
FORCEPROP 1 LAST PATH I54
R 1
J 0
(6325 10750);
DISPLAY 0.978723 (6325 10750);
PAINT WHITE (6325 10750);
DISPLAY INVISIBLE (6325 10750);
FORCEPROP 0 LAST $SEC 1
R 1
J 0
(6300 10800);
DISPLAY 0.680851 (6300 10800);
PAINT MONO (6300 10800);
DISPLAY INVISIBLE (6300 10800);
FORCEPROP 0 LAST CDS_SEC 1
R 1
J 0
(6300 10800);
DISPLAY 1.021277 (6300 10800);
DISPLAY INVISIBLE (6300 10800);
FORCEPROP 1 LASTPIN (6375 10700) $PN 1
R 1
J 0
(6395 10710);
DISPLAY 0.787234 (6395 10710);
PAINT MONO (6395 10710);
DISPLAY INVISIBLE (6395 10710);
FORCEPROP 1 LASTPIN (6575 10700) $PN 2
R 1
J 0
(6595 10710);
DISPLAY 0.787234 (6595 10710);
PAINT MONO (6595 10710);
DISPLAY INVISIBLE (6595 10710);
FORCEADD Q_CAP..1
(6250 11000);
FORCEPROP 1 LAST PART_NUMBER CH5104KEB02
J 0
(6300 10900);
DISPLAY 0.510638 (6300 10900);
DISPLAY INVISIBLE (6300 10900);
FORCEPROP 1 LAST VALUE 1UF
J 0
(6300 11000);
DISPLAY 0.510638 (6300 11000);
FORCEPROP 1 LAST MATERIAL EMPTY
J 0
(6300 10975);
DISPLAY 0.510638 (6300 10975);
PAINT RED (6300 10975);
FORCEPROP 1 LAST PACK_TYPE C0402
J 0
(6300 10925);
DISPLAY 0.510638 (6300 10925);
FORCEPROP 1 LAST VOLTAGE 25V
J 0
(6300 10950);
DISPLAY 0.510638 (6300 10950);
FORCEPROP 2 LAST ROOM NIC1_P12V_MAM_MAM_BOM1
J 0
(6300 11075);
DISPLAY 0.510638 (6300 11075);
FORCEPROP 1 LAST LOCATION PC2085
J 0
(6300 11025);
DISPLAY 0.510638 (6300 11025);
FORCEPROP 2 LAST ROOM1 NIC1_P12V_MAM_TIC_BOM2
J 0
(6300 11125);
DISPLAY 1.021277 (6300 11125);
DISPLAY INVISIBLE (6300 11125);
FORCEPROP 2 LAST CDS_LIB pure_quanta
J 0
(6250 11000);
DISPLAY INVISIBLE (6250 11000);
FORCEPROP 1 LAST TOLERANCE 10%
J 0
(6300 10950);
DISPLAY 0.638298 (6300 10950);
DISPLAY INVISIBLE (6300 10950);
FORCEPROP 1 LAST PATH I55
J 0
(6300 11150);
DISPLAY 0.978723 (6300 11150);
PAINT WHITE (6300 11150);
DISPLAY INVISIBLE (6300 11150);
FORCEPROP 0 LAST $SEC 1
J 0
(6300 11075);
DISPLAY 0.680851 (6300 11075);
PAINT MONO (6300 11075);
DISPLAY INVISIBLE (6300 11075);
FORCEPROP 0 LAST CDS_SEC 1
J 0
(6300 11075);
DISPLAY 1.021277 (6300 11075);
DISPLAY INVISIBLE (6300 11075);
FORCEPROP 1 LASTPIN (6250 11100) $PN 1
J 0
(6260 11080);
DISPLAY 0.787234 (6260 11080);
PAINT MONO (6260 11080);
DISPLAY INVISIBLE (6260 11080);
FORCEPROP 1 LASTPIN (6250 10900) $PN 2
J 0
(6260 10880);
DISPLAY 0.787234 (6260 10880);
PAINT MONO (6260 10880);
DISPLAY INVISIBLE (6260 10880);
FORCEADD Q_RES..2
(6250 11425);
FORCEPROP 1 LAST PART_NUMBER CS01002FB07
J 0
(6300 11375);
DISPLAY 0.510638 (6300 11375);
DISPLAY INVISIBLE (6300 11375);
FORCEPROP 2 LAST ROOM NIC1_P12V_MAM_MAM_BOM1
J 0
(6300 11550);
DISPLAY 0.510638 (6300 11550);
FORCEPROP 1 LAST PACK_TYPE 0402LF
J 0
(6300 11350);
DISPLAY 0.510638 (6300 11350);
FORCEPROP 1 LAST MATERIAL EMPTY
J 0
(6300 11400);
DISPLAY 0.510638 (6300 11400);
PAINT RED (6300 11400);
FORCEPROP 1 LAST WATTAGE 1/16W
J 0
(6300 11425);
DISPLAY 0.510638 (6300 11425);
FORCEPROP 1 LAST VALUE 10
J 0
(6300 11475);
DISPLAY 0.510638 (6300 11475);
FORCEPROP 1 LAST TOLERANCE 1%
J 0
(6300 11450);
DISPLAY 0.510638 (6300 11450);
FORCEPROP 1 LAST LOCATION PR3792
J 0
(6300 11500);
DISPLAY 0.510638 (6300 11500);
FORCEPROP 2 LAST ROOM1 NIC1_P12V_MAM_TIC_BOM2
J 0
(6300 11600);
DISPLAY 1.021277 (6300 11600);
DISPLAY INVISIBLE (6300 11600);
FORCEPROP 2 LAST CDS_LIB pure_quanta
J 0
(6250 11425);
DISPLAY INVISIBLE (6250 11425);
FORCEPROP 1 LAST PATH I56
J 0
(6300 11600);
DISPLAY 0.978723 (6300 11600);
PAINT WHITE (6300 11600);
DISPLAY INVISIBLE (6300 11600);
FORCEPROP 0 LAST $SEC 1
J 0
(6300 11550);
DISPLAY 0.680851 (6300 11550);
PAINT MONO (6300 11550);
DISPLAY INVISIBLE (6300 11550);
FORCEPROP 0 LAST CDS_SEC 1
J 0
(6300 11550);
DISPLAY 1.021277 (6300 11550);
DISPLAY INVISIBLE (6300 11550);
FORCEPROP 1 LASTPIN (6250 11525) $PN 1
J 0
(6255 11487);
DISPLAY 0.787234 (6255 11487);
PAINT MONO (6255 11487);
DISPLAY INVISIBLE (6255 11487);
FORCEPROP 1 LASTPIN (6250 11325) $PN 2
J 0
(6255 11335);
DISPLAY 0.787234 (6255 11335);
PAINT MONO (6255 11335);
DISPLAY INVISIBLE (6255 11335);
FORCEADD GND..1
(6150 12025);
FORCEPROP 3 LASTPIN (6150 12075) SIG_NAME GND\g
J 0
(6160 12085);
DISPLAY 0.659574 (6160 12085);
PAINT MONO (6160 12085);
DISPLAY INVISIBLE (6160 12085);
FORCEPROP 1 LAST HDL_POWER GND
J 0
(6150 12175);
DISPLAY 0.872340 (6150 12175);
PAINT GREEN (6150 12175);
DISPLAY INVISIBLE (6150 12175);
FORCEPROP 1 LAST SIZE 1B
J 0
(6225 11975);
DISPLAY 0.872340 (6225 11975);
PAINT GREEN (6225 11975);
DISPLAY INVISIBLE (6225 11975);
FORCEPROP 2 LAST CDS_LIB logical_power
J 0
(6150 12025);
DISPLAY INVISIBLE (6150 12025);
FORCEPROP 1 LAST PATH I57
J 0
(6225 12025);
DISPLAY 0.872340 (6225 12025);
PAINT AQUA (6225 12025);
DISPLAY INVISIBLE (6225 12025);
FORCEADD Q_RES..2
(6150 12275);
FORCEPROP 1 LAST PART_NUMBER CS31502FB05
J 0
(6200 12225);
DISPLAY 0.404255 (6200 12225);
DISPLAY INVISIBLE (6200 12225);
FORCEPROP 2 LAST ROOM NIC1_P3V3_BOM1
J 0
(6200 12150);
DISPLAY 0.638298 (6200 12150);
FORCEPROP 1 LAST PACK_TYPE 0402LF
J 0
(6200 12200);
DISPLAY 0.404255 (6200 12200);
FORCEPROP 1 LAST MATERIAL CHIP
J 0
(6200 12250);
DISPLAY 0.404255 (6200 12250);
FORCEPROP 1 LAST VALUE 15K
J 0
(6200 12325);
DISPLAY 0.404255 (6200 12325);
FORCEPROP 1 LAST TOLERANCE 1%
J 0
(6200 12300);
DISPLAY 0.404255 (6200 12300);
FORCEPROP 1 LAST WATTAGE 1/16W
J 0
(6200 12275);
DISPLAY 0.404255 (6200 12275);
FORCEPROP 1 LAST LOCATION PR3791
J 0
(6200 12350);
DISPLAY 0.638298 (6200 12350);
FORCEPROP 2 LAST CDS_LIB pure_quanta
J 0
(6150 12275);
DISPLAY INVISIBLE (6150 12275);
FORCEPROP 1 LAST PATH I58
J 0
(6200 12450);
DISPLAY 0.978723 (6200 12450);
PAINT WHITE (6200 12450);
DISPLAY INVISIBLE (6200 12450);
FORCEPROP 0 LAST $SEC 1
J 0
(6200 12400);
DISPLAY 0.680851 (6200 12400);
PAINT MONO (6200 12400);
DISPLAY INVISIBLE (6200 12400);
FORCEPROP 0 LAST CDS_SEC 1
J 0
(6200 12400);
DISPLAY 1.021277 (6200 12400);
DISPLAY INVISIBLE (6200 12400);
FORCEPROP 1 LASTPIN (6150 12375) $PN 1
J 0
(6155 12337);
DISPLAY 0.787234 (6155 12337);
PAINT MONO (6155 12337);
DISPLAY INVISIBLE (6155 12337);
FORCEPROP 1 LASTPIN (6150 12175) $PN 2
J 0
(6155 12185);
DISPLAY 0.787234 (6155 12185);
PAINT MONO (6155 12185);
DISPLAY INVISIBLE (6155 12185);
FORCEADD GND..1
(7000 12000);
FORCEPROP 3 LASTPIN (7000 12050) SIG_NAME GND\g
J 0
(7010 12060);
DISPLAY 0.659574 (7010 12060);
PAINT MONO (7010 12060);
DISPLAY INVISIBLE (7010 12060);
FORCEPROP 2 LAST CDS_LIB logical_power
J 0
(7000 12000);
DISPLAY INVISIBLE (7000 12000);
FORCEPROP 1 LAST HDL_POWER GND
J 0
(7000 12150);
DISPLAY 0.872340 (7000 12150);
PAINT GREEN (7000 12150);
DISPLAY INVISIBLE (7000 12150);
FORCEPROP 1 LAST SIZE 1B
J 0
(7075 11950);
DISPLAY 0.872340 (7075 11950);
PAINT GREEN (7075 11950);
DISPLAY INVISIBLE (7075 11950);
FORCEPROP 1 LAST PATH I59
J 0
(7075 12000);
DISPLAY 0.872340 (7075 12000);
PAINT AQUA (7075 12000);
DISPLAY INVISIBLE (7075 12000);
FORCEADD OFFPAGE..1
(3625 8575);
FORCEPROP 2 LAST $XR1 165 
J 0
(3253 8575);
DISPLAY 0.638298 (3253 8575);
PAINT MONO (3253 8575);
FORCEPROP 2 LAST $XR0 153 
J 0
(3373 8575);
DISPLAY 0.638298 (3373 8575);
PAINT MONO (3373 8575);
FORCEPROP 1 LAST COMMENT_BODY TRUE
J 0
(3750 8475);
DISPLAY 0.872340 (3750 8475);
PAINT GREEN (3750 8475);
DISPLAY INVISIBLE (3750 8475);
FORCEPROP 1 LAST OFFPAGE TRUE
J 0
(3950 8450);
DISPLAY 0.872340 (3950 8450);
PAINT GREEN (3950 8450);
DISPLAY INVISIBLE (3950 8450);
FORCEPROP 2 LAST CDS_LIB standard
J 0
(3625 8575);
PAINT MONO (3625 8575);
DISPLAY INVISIBLE (3625 8575);
FORCEPROP 2 LAST PATH I6
J 0
(3375 8600);
DISPLAY 1.021277 (3375 8600);
DISPLAY INVISIBLE (3375 8600);
FORCEADD Q_RES..2
(7000 12300);
FORCEPROP 1 LAST PART_NUMBER CS25362FB02
J 0
(7050 12225);
DISPLAY 0.510638 (7050 12225);
DISPLAY INVISIBLE (7050 12225);
FORCEPROP 2 LAST ROOM NIC1_P3V3_BOM1
J 0
(7050 12150);
DISPLAY 0.638298 (7050 12150);
FORCEPROP 1 LAST MATERIAL CHIP
J 0
(7050 12250);
DISPLAY 0.510638 (7050 12250);
FORCEPROP 1 LAST PACK_TYPE 0402LF
J 0
(7050 12200);
DISPLAY 0.510638 (7050 12200);
FORCEPROP 1 LAST TOLERANCE 1%
J 0
(7050 12300);
DISPLAY 0.510638 (7050 12300);
FORCEPROP 1 LAST VALUE 5.36K
J 0
(7050 12325);
DISPLAY 0.510638 (7050 12325);
FORCEPROP 1 LAST WATTAGE 1/16W
J 0
(7050 12275);
DISPLAY 0.510638 (7050 12275);
FORCEPROP 1 LAST LOCATION PR3780
J 0
(7050 12350);
DISPLAY 0.638298 (7050 12350);
FORCEPROP 1 LASTPIN (7000 12400) $PN 1
J 0
(7005 12362);
DISPLAY 0.787234 (7005 12362);
PAINT MONO (7005 12362);
FORCEPROP 1 LASTPIN (7000 12200) $PN 2
J 0
(7005 12210);
DISPLAY 0.787234 (7005 12210);
PAINT MONO (7005 12210);
FORCEPROP 2 LAST CDS_LIB pure_quanta
J 0
(7000 12300);
DISPLAY INVISIBLE (7000 12300);
FORCEPROP 1 LAST PATH I60
J 0
(7050 12475);
DISPLAY 0.978723 (7050 12475);
PAINT WHITE (7050 12475);
DISPLAY INVISIBLE (7050 12475);
FORCEPROP 0 LAST $SEC 1
J 0
(7050 12450);
DISPLAY 0.680851 (7050 12450);
PAINT MONO (7050 12450);
DISPLAY INVISIBLE (7050 12450);
FORCEPROP 0 LAST CDS_SEC 1
J 0
(7050 12425);
DISPLAY INVISIBLE (7050 12425);
FORCEADD MAX15090BEWIT..1
(7750 12800);
FORCEPROP 1 LAST PART_NUMBER AL015080B00
J 0
(7497 13444);
DISPLAY 0.723404 (7497 13444);
PAINT GREEN (7497 13444);
DISPLAY INVISIBLE (7497 13444);
FORCEPROP 2 LAST PART_TYPE SMLF
J 0
(7500 13625);
DISPLAY 1.021277 (7500 13625);
FORCEPROP 1 LAST MATERIAL IC
J 0
(7497 13355);
DISPLAY 0.723404 (7497 13355);
PAINT GREEN (7497 13355);
FORCEPROP 2 LAST ROOM NIC1_P3V3_BOM1
J 0
(7500 13675);
DISPLAY 1.021277 (7500 13675);
FORCEPROP 2 LAST VALUE MAX15090BEWI+T
J 0
(7500 13575);
DISPLAY 1.021277 (7500 13575);
FORCEPROP 1 LAST LOCATION PU202
J 0
(7497 13528);
DISPLAY 0.723404 (7497 13528);
PAINT GREEN (7497 13528);
FORCEPROP 0 LASTPIN (7350 12500) $PN B1
J 2
(7340 12510);
DISPLAY 0.680851 (7340 12510);
PAINT MONO (7340 12510);
FORCEPROP 0 LASTPIN (8150 12500) $PN A7
J 0
(8160 12510);
DISPLAY 0.680851 (8160 12510);
PAINT MONO (8160 12510);
FORCEPROP 0 LASTPIN (7350 12400) $PN B7
J 2
(7340 12410);
DISPLAY 0.680851 (7340 12410);
PAINT MONO (7340 12410);
FORCEPROP 0 LASTPIN (8150 12700) $PN C7
J 0
(8160 12710);
DISPLAY 0.680851 (8160 12710);
PAINT MONO (8160 12710);
FORCEPROP 0 LASTPIN (8150 12900) $PN A6
J 0
(8160 12910);
DISPLAY 0.680851 (8160 12910);
PAINT MONO (8160 12910);
FORCEPROP 0 LASTPIN (8150 12400) $PN B2
J 0
(8160 12410);
DISPLAY 0.680851 (8160 12410);
PAINT MONO (8160 12410);
FORCEPROP 0 LASTPIN (8150 12350) $PN C1
J 0
(8160 12360);
DISPLAY 0.680851 (8160 12360);
PAINT MONO (8160 12360);
FORCEPROP 0 LASTPIN (8150 12300) $PN C2
J 0
(8160 12310);
DISPLAY 0.680851 (8160 12310);
PAINT MONO (8160 12310);
FORCEPROP 0 LASTPIN (7350 13300) $PN A3
J 2
(7340 13310);
DISPLAY 0.680851 (7340 13310);
PAINT MONO (7340 13310);
FORCEPROP 0 LASTPIN (7350 13250) $PN A5
J 2
(7340 13260);
DISPLAY 0.680851 (7340 13260);
PAINT MONO (7340 13260);
FORCEPROP 0 LASTPIN (7350 13200) $PN B3
J 2
(7340 13210);
DISPLAY 0.680851 (7340 13210);
PAINT MONO (7340 13210);
FORCEPROP 0 LASTPIN (7350 13150) $PN B5
J 2
(7340 13160);
DISPLAY 0.680851 (7340 13160);
PAINT MONO (7340 13160);
FORCEPROP 0 LASTPIN (7350 13100) $PN C3
J 2
(7340 13110);
DISPLAY 0.680851 (7340 13110);
PAINT MONO (7340 13110);
FORCEPROP 0 LASTPIN (7350 13050) $PN C5
J 2
(7340 13060);
DISPLAY 0.680851 (7340 13060);
PAINT MONO (7340 13060);
FORCEPROP 0 LASTPIN (7350 13000) $PN D5
J 2
(7340 13010);
DISPLAY 0.680851 (7340 13010);
PAINT MONO (7340 13010);
FORCEPROP 0 LASTPIN (8150 12600) $PN A1
J 0
(8160 12610);
DISPLAY 0.680851 (8160 12610);
PAINT MONO (8160 12610);
FORCEPROP 0 LASTPIN (8150 13300) $PN A4
J 0
(8160 13310);
DISPLAY 0.680851 (8160 13310);
PAINT MONO (8160 13310);
FORCEPROP 0 LASTPIN (8150 13250) $PN B4
J 0
(8160 13260);
DISPLAY 0.680851 (8160 13260);
PAINT MONO (8160 13260);
FORCEPROP 0 LASTPIN (8150 13200) $PN B6
J 0
(8160 13210);
DISPLAY 0.680851 (8160 13210);
PAINT MONO (8160 13210);
FORCEPROP 0 LASTPIN (8150 13150) $PN C4
J 0
(8160 13160);
DISPLAY 0.680851 (8160 13160);
PAINT MONO (8160 13160);
FORCEPROP 0 LASTPIN (8150 13100) $PN C6
J 0
(8160 13110);
DISPLAY 0.680851 (8160 13110);
PAINT MONO (8160 13110);
FORCEPROP 0 LASTPIN (8150 13050) $PN D4
J 0
(8160 13060);
DISPLAY 0.680851 (8160 13060);
PAINT MONO (8160 13060);
FORCEPROP 0 LASTPIN (8150 13000) $PN D6
J 0
(8160 13010);
DISPLAY 0.680851 (8160 13010);
PAINT MONO (8160 13010);
FORCEPROP 0 LASTPIN (7350 12600) $PN D3
J 2
(7340 12610);
DISPLAY 0.680851 (7340 12610);
PAINT MONO (7340 12610);
FORCEPROP 0 LASTPIN (8150 12800) $PN D7
J 0
(8160 12810);
DISPLAY 0.680851 (8160 12810);
PAINT MONO (8160 12810);
FORCEPROP 0 LASTPIN (7350 12800) $PN D1
J 2
(7340 12810);
DISPLAY 0.680851 (7340 12810);
PAINT MONO (7340 12810);
FORCEPROP 0 LASTPIN (7350 12700) $PN D2
J 2
(7340 12710);
DISPLAY 0.680851 (7340 12710);
PAINT MONO (7340 12710);
FORCEPROP 0 LASTPIN (7350 12900) $PN A2
J 2
(7340 12910);
DISPLAY 0.680851 (7340 12910);
PAINT MONO (7340 12910);
FORCEPROP 2 LAST CDS_LIB pure_quanta
J 0
(7750 12800);
DISPLAY INVISIBLE (7750 12800);
FORCEPROP 1 LAST PIN_NAMES_ROTATE True
J 0
(7750 12800);
DISPLAY 0.489362 (7750 12800);
PAINT GREEN (7750 12800);
DISPLAY INVISIBLE (7750 12800);
FORCEPROP 1 LAST CDS_LMAN_SYM_OUTLINE -250,550,250,-550
J 0
(7750 12800);
DISPLAY 0.468085 (7750 12800);
PAINT GREEN (7750 12800);
DISPLAY INVISIBLE (7750 12800);
FORCEPROP 1 LAST PATH I61
J 0
(8000 12250);
DISPLAY 0.723404 (8000 12250);
PAINT GREEN (8000 12250);
DISPLAY INVISIBLE (8000 12250);
FORCEPROP 0 LAST $SEC 1
J 0
(7500 13675);
DISPLAY 0.680851 (7500 13675);
PAINT MONO (7500 13675);
DISPLAY INVISIBLE (7500 13675);
FORCEPROP 0 LAST CDS_SEC 1
J 0
(7500 13675);
DISPLAY 1.021277 (7500 13675);
DISPLAY INVISIBLE (7500 13675);
FORCEADD Q_RES..2
(4125 12500);
FORCEPROP 1 LAST PART_NUMBER CS31002FB08
J 0
(4155 12417);
DISPLAY 0.638298 (4155 12417);
DISPLAY INVISIBLE (4155 12417);
FORCEPROP 1 LAST VALUE 10K
J 0
(4160 12617);
DISPLAY 0.638298 (4160 12617);
FORCEPROP 1 LAST TOLERANCE 1%
J 0
(4160 12567);
DISPLAY 0.638298 (4160 12567);
FORCEPROP 2 LAST ROOM NIC1_P3V3_BOM1
J 0
(4175 12700);
DISPLAY 0.808511 (4175 12700);
FORCEPROP 1 LAST PACK_TYPE 0402LF
J 0
(4155 12367);
DISPLAY 0.638298 (4155 12367);
FORCEPROP 1 LAST MATERIAL CHIP
J 0
(4155 12467);
DISPLAY 0.638298 (4155 12467);
FORCEPROP 1 LAST WATTAGE 1/16W
J 0
(4155 12517);
DISPLAY 0.638298 (4155 12517);
FORCEPROP 1 LAST $LOCATION R4070
J 0
(4160 12667);
DISPLAY 0.638298 (4160 12667);
FORCEPROP 1 LASTPIN (4125 12600) $PN 1
J 0
(4130 12562);
DISPLAY 0.787234 (4130 12562);
PAINT MONO (4130 12562);
FORCEPROP 1 LASTPIN (4125 12400) $PN 2
J 0
(4130 12410);
DISPLAY 0.787234 (4130 12410);
PAINT MONO (4130 12410);
FORCEPROP 2 LAST CDS_LIB pure_quanta
J 0
(4125 12500);
DISPLAY INVISIBLE (4125 12500);
FORCEPROP 1 LAST PATH I62
J 0
(4175 12675);
DISPLAY 0.978723 (4175 12675);
PAINT WHITE (4175 12675);
DISPLAY INVISIBLE (4175 12675);
FORCEPROP 0 LAST CDS_LOCATION R4070
J 0
(4175 12700);
DISPLAY 1.021277 (4175 12700);
DISPLAY INVISIBLE (4175 12700);
FORCEPROP 0 LAST $SEC 1
J 0
(4175 12700);
DISPLAY 0.680851 (4175 12700);
PAINT MONO (4175 12700);
DISPLAY INVISIBLE (4175 12700);
FORCEPROP 0 LAST CDS_SEC 1
J 0
(4175 12700);
DISPLAY 1.021277 (4175 12700);
DISPLAY INVISIBLE (4175 12700);
FORCEADD UNIVERSAL_POWER..1
(4125 12750);
FORCEPROP 3 LASTPIN (4125 12700) SIG_NAME P12V_AUX\g
J 0
(4135 12710);
DISPLAY 0.659574 (4135 12710);
PAINT MONO (4135 12710);
DISPLAY INVISIBLE (4135 12710);
FORCEPROP 1 LAST HDL_POWER P12V_AUX
J 1
(4125 12800);
DISPLAY 0.872340 (4125 12800);
PAINT GREEN (4125 12800);
FORCEPROP 2 LAST CDS_LIB logical_power
J 0
(4125 12750);
DISPLAY INVISIBLE (4125 12750);
FORCEPROP 1 LAST PATH I63
J 0
(4175 12775);
DISPLAY 0.872340 (4175 12775);
PAINT AQUA (4175 12775);
DISPLAY INVISIBLE (4175 12775);
FORCEADD Q_RES..1
(5550 12900);
FORCEPROP 1 LAST PART_NUMBER CS00002JB13
J 0
(5475 12850);
DISPLAY 0.510638 (5475 12850);
DISPLAY INVISIBLE (5475 12850);
FORCEPROP 1 LAST PACK_TYPE 0402LF
J 0
(5775 12900);
DISPLAY 0.510638 (5775 12900);
FORCEPROP 1 LAST VALUE 0
J 2
(5675 12900);
DISPLAY 0.510638 (5675 12900);
FORCEPROP 1 LAST WATTAGE 1/16W
J 2
(5725 12825);
DISPLAY 0.510638 (5725 12825);
FORCEPROP 1 LAST TOLERANCE 5%
J 0
(5700 12900);
DISPLAY 0.510638 (5700 12900);
FORCEPROP 1 LAST MATERIAL CHIP
J 0
(5475 12825);
DISPLAY 0.510638 (5475 12825);
FORCEPROP 2 LAST ROOM NIC1_P3V3_BOM1
J 0
(5500 13000);
DISPLAY 0.808511 (5500 13000);
FORCEPROP 1 LAST $LOCATION R3785
J 0
(5500 12950);
DISPLAY 0.978723 (5500 12950);
FORCEPROP 2 LAST CDS_LIB pure_quanta
J 0
(5550 12900);
DISPLAY INVISIBLE (5550 12900);
FORCEPROP 1 LAST PATH I64
J 0
(5500 13050);
DISPLAY 0.978723 (5500 13050);
PAINT WHITE (5500 13050);
DISPLAY INVISIBLE (5500 13050);
FORCEPROP 0 LAST CDS_LOCATION R3785
J 0
(5500 13000);
DISPLAY 1.021277 (5500 13000);
DISPLAY INVISIBLE (5500 13000);
FORCEPROP 0 LAST $SEC 1
J 0
(5500 13000);
DISPLAY 0.680851 (5500 13000);
PAINT MONO (5500 13000);
DISPLAY INVISIBLE (5500 13000);
FORCEPROP 0 LAST CDS_SEC 1
J 0
(5500 13000);
DISPLAY 1.021277 (5500 13000);
DISPLAY INVISIBLE (5500 13000);
FORCEPROP 1 LASTPIN (5450 12900) $PN 1
J 0
(5462 12912);
DISPLAY 0.787234 (5462 12912);
PAINT MONO (5462 12912);
DISPLAY INVISIBLE (5462 12912);
FORCEPROP 1 LASTPIN (5650 12900) $PN 2
J 0
(5612 12912);
DISPLAY 0.787234 (5612 12912);
PAINT MONO (5612 12912);
DISPLAY INVISIBLE (5612 12912);
FORCEADD GND..1
(5800 13250);
FORCEPROP 3 LASTPIN (5800 13300) SIG_NAME GND\g
J 0
(5810 13310);
DISPLAY 0.659574 (5810 13310);
PAINT MONO (5810 13310);
DISPLAY INVISIBLE (5810 13310);
FORCEPROP 1 LAST SIZE 1B
J 0
(5875 13200);
DISPLAY 0.872340 (5875 13200);
PAINT GREEN (5875 13200);
DISPLAY INVISIBLE (5875 13200);
FORCEPROP 1 LAST HDL_POWER GND
J 0
(5800 13400);
DISPLAY 0.872340 (5800 13400);
PAINT GREEN (5800 13400);
DISPLAY INVISIBLE (5800 13400);
FORCEPROP 2 LAST CDS_LIB logical_power
J 0
(5800 13250);
DISPLAY INVISIBLE (5800 13250);
FORCEPROP 1 LAST PATH I65
J 0
(5875 13250);
DISPLAY 0.872340 (5875 13250);
PAINT AQUA (5875 13250);
DISPLAY INVISIBLE (5875 13250);
FORCEADD Q_CAP..1
(5800 13525);
FORCEPROP 1 LAST PART_NUMBER CH5104KEB02
J 0
(5850 13475);
DISPLAY 0.510638 (5850 13475);
DISPLAY INVISIBLE (5850 13475);
FORCEPROP 1 LAST VALUE 1UF
J 0
(5850 13575);
DISPLAY 0.510638 (5850 13575);
FORCEPROP 1 LAST VOLTAGE 25V
J 0
(5850 13550);
DISPLAY 0.510638 (5850 13550);
FORCEPROP 1 LAST MATERIAL X6S
J 0
(5850 13525);
DISPLAY 0.510638 (5850 13525);
FORCEPROP 1 LAST PACK_TYPE C0402
J 0
(5850 13500);
DISPLAY 0.510638 (5850 13500);
FORCEPROP 1 LAST $LOCATION PC5328
J 0
(5850 13600);
DISPLAY 0.638298 (5850 13600);
FORCEPROP 2 LAST CDS_LIB pure_quanta
J 0
(5800 13525);
DISPLAY INVISIBLE (5800 13525);
FORCEPROP 1 LAST TOLERANCE 10%
J 0
(5850 13475);
DISPLAY 0.638298 (5850 13475);
DISPLAY INVISIBLE (5850 13475);
FORCEPROP 1 LAST PATH I66
J 0
(5850 13675);
DISPLAY 0.978723 (5850 13675);
PAINT WHITE (5850 13675);
DISPLAY INVISIBLE (5850 13675);
FORCEPROP 0 LAST CDS_LOCATION PC5328
J 0
(5850 13650);
DISPLAY 1.021277 (5850 13650);
DISPLAY INVISIBLE (5850 13650);
FORCEPROP 0 LAST $SEC 1
J 0
(5855 13667);
DISPLAY INVISIBLE (5855 13667);
FORCEPROP 0 LAST CDS_SEC 1
J 0
(5855 13667);
DISPLAY INVISIBLE (5855 13667);
FORCEPROP 1 LASTPIN (5800 13625) $PN 1
J 0
(5810 13605);
DISPLAY 0.787234 (5810 13605);
PAINT MONO (5810 13605);
DISPLAY INVISIBLE (5810 13605);
FORCEPROP 1 LASTPIN (5800 13425) $PN 2
J 0
(5810 13405);
DISPLAY 0.787234 (5810 13405);
PAINT MONO (5810 13405);
DISPLAY INVISIBLE (5810 13405);
FORCEADD UNIVERSAL_POWER..1
(5800 13875);
FORCEPROP 3 LASTPIN (5800 13825) SIG_NAME P3V3_AUX\g
J 0
(5810 13835);
DISPLAY 0.659574 (5810 13835);
PAINT MONO (5810 13835);
DISPLAY INVISIBLE (5810 13835);
FORCEPROP 1 LAST HDL_POWER P3V3_AUX
J 1
(5800 13925);
DISPLAY 0.872340 (5800 13925);
PAINT GREEN (5800 13925);
FORCEPROP 2 LAST CDS_LIB logical_power
J 0
(5800 13875);
DISPLAY INVISIBLE (5800 13875);
FORCEPROP 1 LAST PATH I67
J 0
(5850 13900);
DISPLAY 0.872340 (5850 13900);
PAINT AQUA (5850 13900);
DISPLAY INVISIBLE (5850 13900);
FORCEADD Q_RES..2
(6150 12550);
FORCEPROP 1 LAST PART_NUMBER CS27152FB03
J 0
(6200 12500);
DISPLAY 0.404255 (6200 12500);
DISPLAY INVISIBLE (6200 12500);
FORCEPROP 2 LAST ROOM NIC1_P3V3_BOM1
J 0
(6200 12425);
DISPLAY 0.638298 (6200 12425);
FORCEPROP 1 LAST MATERIAL CHIP
J 0
(6200 12525);
DISPLAY 0.404255 (6200 12525);
FORCEPROP 1 LAST WATTAGE 1/16W
J 0
(6200 12550);
DISPLAY 0.404255 (6200 12550);
FORCEPROP 1 LAST TOLERANCE 1%
J 0
(6200 12575);
DISPLAY 0.404255 (6200 12575);
FORCEPROP 1 LAST VALUE 7.15K
J 0
(6200 12600);
DISPLAY 0.404255 (6200 12600);
FORCEPROP 1 LAST PACK_TYPE 0402LF
J 0
(6200 12475);
DISPLAY 0.404255 (6200 12475);
FORCEPROP 1 LAST LOCATION PR3790
J 0
(6200 12625);
DISPLAY 0.638298 (6200 12625);
FORCEPROP 2 LAST CDS_LIB pure_quanta
J 0
(6150 12550);
DISPLAY INVISIBLE (6150 12550);
FORCEPROP 1 LAST PATH I68
J 0
(6200 12725);
DISPLAY 0.978723 (6200 12725);
PAINT WHITE (6200 12725);
DISPLAY INVISIBLE (6200 12725);
FORCEPROP 0 LAST $SEC 1
J 0
(6200 12675);
DISPLAY 0.680851 (6200 12675);
PAINT MONO (6200 12675);
DISPLAY INVISIBLE (6200 12675);
FORCEPROP 0 LAST CDS_SEC 1
J 0
(6200 12675);
DISPLAY 1.021277 (6200 12675);
DISPLAY INVISIBLE (6200 12675);
FORCEPROP 1 LASTPIN (6150 12650) $PN 1
J 0
(6155 12612);
DISPLAY 0.787234 (6155 12612);
PAINT MONO (6155 12612);
DISPLAY INVISIBLE (6155 12612);
FORCEPROP 1 LASTPIN (6150 12450) $PN 2
J 0
(6155 12460);
DISPLAY 0.787234 (6155 12460);
PAINT MONO (6155 12460);
DISPLAY INVISIBLE (6155 12460);
FORCEADD GND..1
(6475 12725);
FORCEPROP 3 LASTPIN (6475 12775) SIG_NAME GND\g
J 0
(6485 12785);
DISPLAY 0.659574 (6485 12785);
PAINT MONO (6485 12785);
DISPLAY INVISIBLE (6485 12785);
FORCEPROP 2 LAST CDS_LIB logical_power
J 0
(6475 12725);
DISPLAY INVISIBLE (6475 12725);
FORCEPROP 1 LAST SIZE 1B
J 0
(6550 12675);
DISPLAY 0.872340 (6550 12675);
PAINT GREEN (6550 12675);
DISPLAY INVISIBLE (6550 12675);
FORCEPROP 1 LAST HDL_POWER GND
J 0
(6475 12875);
DISPLAY 0.872340 (6475 12875);
PAINT GREEN (6475 12875);
DISPLAY INVISIBLE (6475 12875);
FORCEPROP 1 LAST PATH I69
J 0
(6550 12725);
DISPLAY 0.872340 (6550 12725);
PAINT AQUA (6550 12725);
DISPLAY INVISIBLE (6550 12725);
FORCEADD Q_RES..2
(3800 8825);
FORCEPROP 1 LAST PART_NUMBER CS21002FB06
J 0
(3840 8700);
DISPLAY 0.638298 (3840 8700);
DISPLAY INVISIBLE (3840 8700);
FORCEPROP 1 LAST WATTAGE 1/16W
J 0
(3840 8800);
DISPLAY 0.510638 (3840 8800);
FORCEPROP 1 LAST MATERIAL CHIP
J 0
(3840 8750);
DISPLAY 0.510638 (3840 8750);
FORCEPROP 1 LAST TOLERANCE 1%
J 0
(3845 8850);
DISPLAY 0.510638 (3845 8850);
FORCEPROP 1 LAST VALUE 1K
J 0
(3845 8900);
DISPLAY 0.510638 (3845 8900);
FORCEPROP 1 LAST PACK_TYPE 0402LF
J 0
(3840 8700);
DISPLAY 0.510638 (3840 8700);
FORCEPROP 1 LAST LOCATION R1906
J 0
(3845 8950);
DISPLAY 0.510638 (3845 8950);
FORCEPROP 1 LASTPIN (3800 8925) $PN 1
J 0
(3805 8887);
DISPLAY 0.510638 (3805 8887);
PAINT MONO (3805 8887);
FORCEPROP 1 LASTPIN (3800 8725) $PN 2
J 0
(3805 8735);
DISPLAY 0.510638 (3805 8735);
PAINT MONO (3805 8735);
FORCEPROP 2 LAST CDS_LIB pure_quanta
J 0
(3800 8825);
DISPLAY INVISIBLE (3800 8825);
FORCEPROP 1 LAST PATH I7
J 0
(3850 9000);
DISPLAY 0.978723 (3850 9000);
PAINT WHITE (3850 9000);
DISPLAY INVISIBLE (3850 9000);
FORCEPROP 0 LAST $SEC 1
J 0
(3850 9000);
DISPLAY 0.680851 (3850 9000);
PAINT MONO (3850 9000);
DISPLAY INVISIBLE (3850 9000);
FORCEPROP 0 LAST CDS_SEC 1
J 0
(3850 9000);
DISPLAY 1.021277 (3850 9000);
DISPLAY INVISIBLE (3850 9000);
FORCEADD Q_RES..2
(6150 13275);
FORCEPROP 1 LAST PART_NUMBER CS32552FB06
J 0
(6200 13225);
DISPLAY 0.404255 (6200 13225);
DISPLAY INVISIBLE (6200 13225);
FORCEPROP 1 LAST MATERIAL CHIP
J 0
(6200 13250);
DISPLAY 0.404255 (6200 13250);
FORCEPROP 1 LAST TOLERANCE 1%
J 0
(6200 13300);
DISPLAY 0.404255 (6200 13300);
FORCEPROP 1 LAST VALUE 25.5K
J 0
(6200 13325);
DISPLAY 0.404255 (6200 13325);
FORCEPROP 1 LAST WATTAGE 1/16W
J 0
(6200 13275);
DISPLAY 0.404255 (6200 13275);
FORCEPROP 2 LAST ROOM NIC1_P3V3_BOM1
J 0
(6200 13400);
DISPLAY 0.510638 (6200 13400);
FORCEPROP 1 LAST PACK_TYPE 0402LF
J 0
(6200 13200);
DISPLAY 0.404255 (6200 13200);
FORCEPROP 1 LAST LOCATION PR3789
J 0
(6200 13350);
DISPLAY 0.638298 (6200 13350);
FORCEPROP 1 LAST PATH I70
J 0
(6200 13450);
DISPLAY 0.978723 (6200 13450);
PAINT WHITE (6200 13450);
DISPLAY INVISIBLE (6200 13450);
FORCEPROP 2 LAST CDS_LIB pure_quanta
J 0
(6150 13275);
DISPLAY INVISIBLE (6150 13275);
FORCEPROP 0 LAST $SEC 1
J 0
(6200 13400);
DISPLAY 0.680851 (6200 13400);
PAINT MONO (6200 13400);
DISPLAY INVISIBLE (6200 13400);
FORCEPROP 0 LAST CDS_SEC 1
J 0
(6200 13400);
DISPLAY 1.021277 (6200 13400);
DISPLAY INVISIBLE (6200 13400);
FORCEPROP 1 LASTPIN (6150 13375) $PN 1
J 0
(6155 13337);
DISPLAY 0.787234 (6155 13337);
PAINT MONO (6155 13337);
DISPLAY INVISIBLE (6155 13337);
FORCEPROP 1 LASTPIN (6150 13175) $PN 2
J 0
(6155 13185);
DISPLAY 0.787234 (6155 13185);
PAINT MONO (6155 13185);
DISPLAY INVISIBLE (6155 13185);
FORCEADD Q_CAP..1
(6475 13100);
FORCEPROP 1 LAST PART_NUMBER CH5104KEB02
J 0
(6525 13000);
DISPLAY 0.510638 (6525 13000);
DISPLAY INVISIBLE (6525 13000);
FORCEPROP 1 LAST PACK_TYPE C0402
J 0
(6525 13025);
DISPLAY 0.510638 (6525 13025);
FORCEPROP 1 LAST VALUE 1UF
J 0
(6525 13100);
DISPLAY 0.510638 (6525 13100);
FORCEPROP 1 LAST MATERIAL X6S
J 0
(6525 13075);
DISPLAY 0.510638 (6525 13075);
FORCEPROP 1 LAST VOLTAGE 25V
J 0
(6525 13050);
DISPLAY 0.510638 (6525 13050);
FORCEPROP 2 LAST ROOM NIC1_P3V3_BOM1
J 0
(6500 13175);
DISPLAY 0.510638 (6500 13175);
FORCEPROP 1 LAST LOCATION PC2086
J 0
(6525 13125);
DISPLAY 0.638298 (6525 13125);
FORCEPROP 1 LAST TOLERANCE 10%
J 0
(6525 13050);
DISPLAY 0.638298 (6525 13050);
DISPLAY INVISIBLE (6525 13050);
FORCEPROP 2 LAST CDS_LIB pure_quanta
J 0
(6475 13100);
DISPLAY INVISIBLE (6475 13100);
FORCEPROP 1 LAST PATH I71
J 0
(6525 13250);
DISPLAY 0.978723 (6525 13250);
PAINT WHITE (6525 13250);
DISPLAY INVISIBLE (6525 13250);
FORCEPROP 0 LAST $SEC 1
J 0
(6525 13175);
DISPLAY 0.680851 (6525 13175);
PAINT MONO (6525 13175);
DISPLAY INVISIBLE (6525 13175);
FORCEPROP 0 LAST CDS_SEC 1
J 0
(6525 13175);
DISPLAY 1.021277 (6525 13175);
DISPLAY INVISIBLE (6525 13175);
FORCEPROP 1 LASTPIN (6475 13200) $PN 1
J 0
(6485 13180);
DISPLAY 0.787234 (6485 13180);
PAINT MONO (6485 13180);
DISPLAY INVISIBLE (6485 13180);
FORCEPROP 1 LASTPIN (6475 13000) $PN 2
J 0
(6485 12980);
DISPLAY 0.787234 (6485 12980);
PAINT MONO (6485 12980);
DISPLAY INVISIBLE (6485 12980);
FORCEADD Q_CAP..1
R 1
(6700 12800);
FORCEPROP 1 LAST PART_NUMBER CH5104KEB02
J 0
(6750 12750);
DISPLAY 0.510638 (6750 12750);
DISPLAY INVISIBLE (6750 12750);
FORCEPROP 1 LAST VALUE 1UF
J 0
(6675 12850);
DISPLAY 0.510638 (6675 12850);
FORCEPROP 1 LAST PACK_TYPE C0402
J 0
(6525 12750);
DISPLAY 0.510638 (6525 12750);
FORCEPROP 1 LAST VOLTAGE 25V
J 0
(6825 12850);
DISPLAY 0.510638 (6825 12850);
FORCEPROP 2 LAST ROOM NIC1_P3V3_BOM1
J 0
(6525 12900);
DISPLAY 0.638298 (6525 12900);
FORCEPROP 1 LAST LOCATION PC2093
J 0
(6525 12850);
DISPLAY 0.638298 (6525 12850);
FORCEPROP 1 LAST TOLERANCE 10%
R 1
J 0
(6750 12850);
DISPLAY 0.638298 (6750 12850);
DISPLAY INVISIBLE (6750 12850);
FORCEPROP 2 LAST CDS_LIB pure_quanta
J 0
(6700 12800);
DISPLAY INVISIBLE (6700 12800);
FORCEPROP 1 LAST MATERIAL X6S
R 1
J 0
(6700 12850);
DISPLAY 0.638298 (6700 12850);
DISPLAY INVISIBLE (6700 12850);
FORCEPROP 1 LAST PATH I72
R 1
J 0
(6550 12850);
DISPLAY 0.978723 (6550 12850);
PAINT WHITE (6550 12850);
DISPLAY INVISIBLE (6550 12850);
FORCEPROP 0 LAST $SEC 1
R 1
J 0
(6525 12900);
DISPLAY 0.680851 (6525 12900);
PAINT MONO (6525 12900);
DISPLAY INVISIBLE (6525 12900);
FORCEPROP 0 LAST CDS_SEC 1
R 1
J 0
(6525 12900);
DISPLAY 1.021277 (6525 12900);
DISPLAY INVISIBLE (6525 12900);
FORCEPROP 1 LASTPIN (6600 12800) $PN 1
R 1
J 0
(6620 12810);
DISPLAY 0.787234 (6620 12810);
PAINT MONO (6620 12810);
DISPLAY INVISIBLE (6620 12810);
FORCEPROP 1 LASTPIN (6800 12800) $PN 2
R 1
J 0
(6820 12810);
DISPLAY 0.787234 (6820 12810);
PAINT MONO (6820 12810);
DISPLAY INVISIBLE (6820 12810);
FORCEADD Q_RES..2
(6475 13525);
FORCEPROP 1 LAST PART_NUMBER CS01002FB07
J 0
(6525 13475);
DISPLAY 0.404255 (6525 13475);
DISPLAY INVISIBLE (6525 13475);
FORCEPROP 1 LAST WATTAGE 1/16W
J 0
(6525 13525);
DISPLAY 0.404255 (6525 13525);
FORCEPROP 1 LAST TOLERANCE 1%
J 0
(6525 13550);
DISPLAY 0.404255 (6525 13550);
FORCEPROP 1 LAST VALUE 10
J 0
(6525 13575);
DISPLAY 0.404255 (6525 13575);
FORCEPROP 1 LAST PACK_TYPE 0402LF
J 0
(6525 13450);
DISPLAY 0.404255 (6525 13450);
FORCEPROP 1 LAST MATERIAL CHIP
J 0
(6525 13500);
DISPLAY 0.404255 (6525 13500);
FORCEPROP 2 LAST ROOM NIC1_P3V3_BOM1
J 0
(6525 13650);
DISPLAY 0.638298 (6525 13650);
FORCEPROP 1 LAST LOCATION PR3798
J 0
(6525 13600);
DISPLAY 0.638298 (6525 13600);
FORCEPROP 2 LAST CDS_LIB pure_quanta
J 0
(6475 13525);
DISPLAY INVISIBLE (6475 13525);
FORCEPROP 1 LAST PATH I73
J 0
(6525 13700);
DISPLAY 0.978723 (6525 13700);
PAINT WHITE (6525 13700);
DISPLAY INVISIBLE (6525 13700);
FORCEPROP 0 LAST $SEC 1
J 0
(6525 13650);
DISPLAY 0.680851 (6525 13650);
PAINT MONO (6525 13650);
DISPLAY INVISIBLE (6525 13650);
FORCEPROP 0 LAST CDS_SEC 1
J 0
(6525 13650);
DISPLAY 1.021277 (6525 13650);
DISPLAY INVISIBLE (6525 13650);
FORCEPROP 1 LASTPIN (6475 13625) $PN 1
J 0
(6480 13587);
DISPLAY 0.787234 (6480 13587);
PAINT MONO (6480 13587);
DISPLAY INVISIBLE (6480 13587);
FORCEPROP 1 LASTPIN (6475 13425) $PN 2
J 0
(6480 13435);
DISPLAY 0.787234 (6480 13435);
PAINT MONO (6480 13435);
DISPLAY INVISIBLE (6480 13435);
FORCEADD Q_RES..2
(8250 9300);
FORCEPROP 1 LAST PART_NUMBER CS31002FB08
J 0
(8290 9125);
DISPLAY 0.510638 (8290 9125);
DISPLAY INVISIBLE (8290 9125);
FORCEPROP 1 LAST TOLERANCE 1%
J 0
(8295 9325);
DISPLAY 0.510638 (8295 9325);
FORCEPROP 1 LAST WATTAGE 1/16W
J 0
(8290 9275);
DISPLAY 0.510638 (8290 9275);
FORCEPROP 1 LAST VALUE 10K
J 0
(8295 9375);
DISPLAY 0.510638 (8295 9375);
FORCEPROP 1 LAST MATERIAL CHIP
J 0
(8290 9225);
DISPLAY 0.510638 (8290 9225);
FORCEPROP 1 LAST PACK_TYPE 0402LF
J 0
(8290 9175);
DISPLAY 0.510638 (8290 9175);
FORCEPROP 1 LAST $LOCATION R1150
J 0
(8295 9425);
DISPLAY 0.510638 (8295 9425);
FORCEPROP 1 LASTPIN (8250 9400) $PN 1
J 0
(8255 9362);
DISPLAY 0.510638 (8255 9362);
FORCEPROP 1 LASTPIN (8250 9200) $PN 2
J 0
(8255 9210);
DISPLAY 0.510638 (8255 9210);
FORCEPROP 2 LAST CDS_LIB pure_quanta
J 0
(8250 9300);
PAINT MONO (8250 9300);
DISPLAY INVISIBLE (8250 9300);
FORCEPROP 1 LAST PATH I74
J 0
(8300 9475);
DISPLAY 0.978723 (8300 9475);
PAINT WHITE (8300 9475);
DISPLAY INVISIBLE (8300 9475);
FORCEPROP 2 LAST CDS_LOCATION R1150
J 0
(8300 9525);
DISPLAY 1.021277 (8300 9525);
DISPLAY INVISIBLE (8300 9525);
FORCEPROP 2 LAST $SEC 1
J 0
(8300 9525);
DISPLAY 0.680851 (8300 9525);
PAINT MONO (8300 9525);
DISPLAY INVISIBLE (8300 9525);
FORCEPROP 2 LAST CDS_SEC 1
J 0
(8300 9525);
DISPLAY 1.021277 (8300 9525);
DISPLAY INVISIBLE (8300 9525);
FORCEADD OFFPAGE..2
(9100 8725);
FORCEPROP 2 LAST $XR0 216 
J 0
(9289 8725);
DISPLAY 0.638298 (9289 8725);
PAINT MONO (9289 8725);
FORCEPROP 2 LAST CDS_LIB standard
J 0
(9100 8725);
PAINT MONO (9100 8725);
DISPLAY INVISIBLE (9100 8725);
FORCEPROP 1 LAST OFFPAGE TRUE
J 0
(9425 8600);
DISPLAY 0.872340 (9425 8600);
DISPLAY INVISIBLE (9425 8600);
FORCEPROP 1 LAST COMMENT_BODY TRUE
J 0
(9055 8630);
DISPLAY 0.872340 (9055 8630);
PAINT GREEN (9055 8630);
DISPLAY INVISIBLE (9055 8630);
FORCEPROP 2 LAST PATH I75
J 0
(9300 8775);
DISPLAY 1.021277 (9300 8775);
DISPLAY INVISIBLE (9300 8775);
FORCEADD Q_RES..2
(8600 9300);
FORCEPROP 1 LAST PART_NUMBER CS31002FB08
J 0
(8640 9125);
DISPLAY 0.510638 (8640 9125);
DISPLAY INVISIBLE (8640 9125);
FORCEPROP 1 LAST MATERIAL CHIP
J 0
(8640 9225);
DISPLAY 0.510638 (8640 9225);
FORCEPROP 1 LAST WATTAGE 1/16W
J 0
(8640 9275);
DISPLAY 0.510638 (8640 9275);
FORCEPROP 1 LAST PACK_TYPE 0402LF
J 0
(8640 9175);
DISPLAY 0.510638 (8640 9175);
FORCEPROP 1 LAST TOLERANCE 1%
J 0
(8645 9325);
DISPLAY 0.510638 (8645 9325);
FORCEPROP 1 LAST VALUE 10K
J 0
(8645 9375);
DISPLAY 0.510638 (8645 9375);
FORCEPROP 1 LAST $LOCATION R4762
J 0
(8645 9425);
DISPLAY 0.978723 (8645 9425);
FORCEPROP 1 LASTPIN (8600 9400) $PN 1
J 0
(8605 9362);
DISPLAY 0.787234 (8605 9362);
PAINT MONO (8605 9362);
FORCEPROP 1 LASTPIN (8600 9200) $PN 2
J 0
(8605 9210);
DISPLAY 0.787234 (8605 9210);
PAINT MONO (8605 9210);
FORCEPROP 2 LAST CDS_LIB pure_quanta
J 0
(8600 9300);
DISPLAY INVISIBLE (8600 9300);
FORCEPROP 1 LAST PATH I76
J 0
(8650 9475);
DISPLAY 0.978723 (8650 9475);
PAINT WHITE (8650 9475);
DISPLAY INVISIBLE (8650 9475);
FORCEPROP 0 LAST CDS_LOCATION R4762
J 0
(8650 9475);
DISPLAY 1.021277 (8650 9475);
DISPLAY INVISIBLE (8650 9475);
FORCEPROP 0 LAST $SEC 1
J 0
(8650 9475);
DISPLAY 0.680851 (8650 9475);
PAINT MONO (8650 9475);
DISPLAY INVISIBLE (8650 9475);
FORCEPROP 0 LAST CDS_SEC 1
J 0
(8650 9475);
DISPLAY 1.021277 (8650 9475);
DISPLAY INVISIBLE (8650 9475);
FORCEADD OFFPAGE..2
(9100 9025);
FORCEPROP 2 LAST $XR0 158 
J 0
(9289 9025);
DISPLAY 0.638298 (9289 9025);
PAINT MONO (9289 9025);
FORCEPROP 2 LAST CDS_LIB standard
J 0
(9100 9025);
PAINT MONO (9100 9025);
DISPLAY INVISIBLE (9100 9025);
FORCEPROP 1 LAST OFFPAGE TRUE
J 0
(9425 8900);
DISPLAY 0.872340 (9425 8900);
DISPLAY INVISIBLE (9425 8900);
FORCEPROP 1 LAST COMMENT_BODY TRUE
J 0
(9055 8930);
DISPLAY 0.872340 (9055 8930);
PAINT GREEN (9055 8930);
DISPLAY INVISIBLE (9055 8930);
FORCEPROP 2 LAST PATH I77
J 0
(9300 9050);
DISPLAY 1.021277 (9300 9050);
DISPLAY INVISIBLE (9300 9050);
FORCEADD OFFPAGE..2
(9100 8875);
FORCEPROP 2 LAST $XR0 158 
J 0
(9289 8875);
DISPLAY 0.638298 (9289 8875);
PAINT MONO (9289 8875);
FORCEPROP 2 LAST CDS_LIB standard
J 0
(9100 8875);
PAINT MONO (9100 8875);
DISPLAY INVISIBLE (9100 8875);
FORCEPROP 1 LAST OFFPAGE TRUE
J 0
(9425 8750);
DISPLAY 0.872340 (9425 8750);
DISPLAY INVISIBLE (9425 8750);
FORCEPROP 1 LAST COMMENT_BODY TRUE
J 0
(9055 8780);
DISPLAY 0.872340 (9055 8780);
PAINT GREEN (9055 8780);
DISPLAY INVISIBLE (9055 8780);
FORCEPROP 2 LAST PATH I78
J 0
(9300 8900);
DISPLAY 1.021277 (9300 8900);
DISPLAY INVISIBLE (9300 8900);
FORCEADD GND..1
(8250 10025);
FORCEPROP 3 LASTPIN (8250 10075) SIG_NAME GND\g
J 0
(8260 10085);
DISPLAY 0.659574 (8260 10085);
PAINT MONO (8260 10085);
DISPLAY INVISIBLE (8260 10085);
FORCEPROP 1 LAST HDL_POWER GND
J 0
(8250 10175);
DISPLAY 0.872340 (8250 10175);
PAINT GREEN (8250 10175);
DISPLAY INVISIBLE (8250 10175);
FORCEPROP 2 LAST CDS_LIB logical_power
J 0
(8250 10025);
DISPLAY INVISIBLE (8250 10025);
FORCEPROP 1 LAST SIZE 1B
J 0
(8325 9975);
DISPLAY 0.872340 (8325 9975);
PAINT GREEN (8325 9975);
DISPLAY INVISIBLE (8325 9975);
FORCEPROP 1 LAST PATH I79
J 0
(8325 10025);
DISPLAY 0.872340 (8325 10025);
PAINT AQUA (8325 10025);
DISPLAY INVISIBLE (8325 10025);
FORCEADD UNIVERSAL_POWER..1
(3800 9125);
FORCEPROP 3 LASTPIN (3800 9075) SIG_NAME P3V3_AUX\g
J 0
(3810 9085);
DISPLAY 0.659574 (3810 9085);
PAINT MONO (3810 9085);
DISPLAY INVISIBLE (3810 9085);
FORCEPROP 1 LAST HDL_POWER P3V3_AUX
J 1
(3800 9175);
DISPLAY 0.510638 (3800 9175);
PAINT GREEN (3800 9175);
FORCEPROP 2 LAST CDS_LIB logical_power
J 0
(3800 9125);
DISPLAY INVISIBLE (3800 9125);
FORCEPROP 1 LAST PATH I8
J 0
(3850 9150);
DISPLAY 0.872340 (3850 9150);
PAINT AQUA (3850 9150);
DISPLAY INVISIBLE (3850 9150);
FORCEADD Q_RES..2
(8375 10300);
FORCEPROP 1 LAST PART_NUMBER CS18452FB01
J 0
(8415 10175);
DISPLAY 0.510638 (8415 10175);
DISPLAY INVISIBLE (8415 10175);
FORCEPROP 1 LAST VALUE 845
J 0
(8420 10375);
DISPLAY 0.510638 (8420 10375);
FORCEPROP 1 LAST TOLERANCE 1%
J 0
(8420 10325);
DISPLAY 0.510638 (8420 10325);
FORCEPROP 1 LAST PACK_TYPE 0402LF
J 0
(8415 10125);
DISPLAY 0.510638 (8415 10125);
FORCEPROP 2 LAST ROOM NIC1_P12V_MAM_MAM_BOM1
J 0
(8425 10075);
DISPLAY 0.510638 (8425 10075);
FORCEPROP 1 LAST MATERIAL EMPTY
J 0
(8415 10225);
DISPLAY 0.510638 (8415 10225);
PAINT RED (8415 10225);
FORCEPROP 1 LAST WATTAGE 1/16W
J 0
(8415 10275);
DISPLAY 0.510638 (8415 10275);
FORCEPROP 1 LAST LOCATION PR3781
J 0
(8420 10425);
DISPLAY 0.510638 (8420 10425);
FORCEPROP 1 LASTPIN (8375 10400) $PN 1
J 0
(8380 10362);
DISPLAY 0.510638 (8380 10362);
PAINT MONO (8380 10362);
FORCEPROP 1 LASTPIN (8375 10200) $PN 2
J 0
(8380 10210);
DISPLAY 0.510638 (8380 10210);
PAINT MONO (8380 10210);
FORCEPROP 2 LAST ROOM1 NIC1_P12V_MAM_TIC_BOM2
J 0
(8425 10525);
DISPLAY 1.021277 (8425 10525);
DISPLAY INVISIBLE (8425 10525);
FORCEPROP 2 LAST CDS_LIB pure_quanta
J 0
(8375 10300);
DISPLAY INVISIBLE (8375 10300);
FORCEPROP 1 LAST PATH I80
J 0
(8425 10475);
DISPLAY 0.978723 (8425 10475);
PAINT WHITE (8425 10475);
DISPLAY INVISIBLE (8425 10475);
FORCEPROP 0 LAST $SEC 1
J 0
(8425 10475);
DISPLAY 0.680851 (8425 10475);
PAINT MONO (8425 10475);
DISPLAY INVISIBLE (8425 10475);
FORCEPROP 0 LAST CDS_SEC 1
J 0
(8425 10475);
DISPLAY 1.021277 (8425 10475);
DISPLAY INVISIBLE (8425 10475);
FORCEADD Q_CAP..1
(8300 11025);
FORCEPROP 1 LAST PART_NUMBER CH31006KB18
J 0
(8355 10917);
DISPLAY 0.510638 (8355 10917);
DISPLAY INVISIBLE (8355 10917);
FORCEPROP 1 LAST PACK_TYPE C0402
J 0
(8355 10967);
DISPLAY 0.510638 (8355 10967);
FORCEPROP 1 LAST VALUE 0.01UF
J 0
(8350 11075);
DISPLAY 0.510638 (8350 11075);
FORCEPROP 1 LAST VOLTAGE 50V
J 0
(8355 11017);
DISPLAY 0.510638 (8355 11017);
FORCEPROP 1 LAST MATERIAL EMPTY
J 0
(8350 10875);
DISPLAY 0.510638 (8350 10875);
PAINT RED (8350 10875);
FORCEPROP 1 LAST LOCATION PC2088
J 0
(8350 11125);
DISPLAY 0.510638 (8350 11125);
FORCEPROP 1 LAST TOLERANCE 10%
J 0
(8350 10975);
DISPLAY 0.638298 (8350 10975);
DISPLAY INVISIBLE (8350 10975);
FORCEPROP 2 LAST CDS_LIB pure_quanta
J 0
(8300 11025);
DISPLAY INVISIBLE (8300 11025);
FORCEPROP 1 LAST PATH I81
J 0
(8350 11175);
DISPLAY 0.978723 (8350 11175);
PAINT WHITE (8350 11175);
DISPLAY INVISIBLE (8350 11175);
FORCEPROP 0 LAST $SEC 1
J 0
(8350 11175);
DISPLAY 0.680851 (8350 11175);
PAINT MONO (8350 11175);
DISPLAY INVISIBLE (8350 11175);
FORCEPROP 0 LAST CDS_SEC 1
J 0
(8350 11175);
DISPLAY 1.021277 (8350 11175);
DISPLAY INVISIBLE (8350 11175);
FORCEPROP 1 LASTPIN (8300 11125) $PN 1
J 0
(8310 11105);
DISPLAY 0.787234 (8310 11105);
PAINT MONO (8310 11105);
DISPLAY INVISIBLE (8310 11105);
FORCEPROP 1 LASTPIN (8300 10925) $PN 2
J 0
(8310 10905);
DISPLAY 0.787234 (8310 10905);
PAINT MONO (8310 10905);
DISPLAY INVISIBLE (8310 10905);
FORCEADD Q_RES..1
(9025 10700);
FORCEPROP 1 LAST PART_NUMBER CS00002JB13
J 0
(8850 10650);
DISPLAY 0.510638 (8850 10650);
DISPLAY INVISIBLE (8850 10650);
FORCEPROP 2 LAST ROOM NIC1_P12V_MAM_MAM_BOM1
J 0
(9200 10750);
DISPLAY 0.510638 (9200 10750);
FORCEPROP 1 LAST PACK_TYPE 0402LF
J 0
(9175 10650);
DISPLAY 0.510638 (9175 10650);
FORCEPROP 1 LAST TOLERANCE 5%
J 0
(9200 10700);
DISPLAY 0.510638 (9200 10700);
FORCEPROP 1 LAST VALUE 0
J 2
(9175 10700);
DISPLAY 0.510638 (9175 10700);
FORCEPROP 1 LAST MATERIAL EMPTY
J 0
(8800 10700);
DISPLAY 0.510638 (8800 10700);
PAINT RED (8800 10700);
FORCEPROP 1 LAST WATTAGE 1/16W
J 2
(8825 10650);
DISPLAY 0.510638 (8825 10650);
FORCEPROP 1 LAST LOCATION R3144
J 0
(8675 10700);
DISPLAY 0.510638 (8675 10700);
FORCEPROP 2 LAST ROOM1 NIC1_P12V_MAM_TIC_BOM2
J 0
(9200 10800);
DISPLAY 1.021277 (9200 10800);
DISPLAY INVISIBLE (9200 10800);
FORCEPROP 2 LAST CDS_LIB pure_quanta
J 0
(9025 10700);
DISPLAY INVISIBLE (9025 10700);
FORCEPROP 1 LAST PATH I82
J 0
(8975 10850);
DISPLAY 0.978723 (8975 10850);
PAINT WHITE (8975 10850);
DISPLAY INVISIBLE (8975 10850);
FORCEPROP 0 LAST $SEC 1
J 0
(9000 10775);
DISPLAY 0.680851 (9000 10775);
PAINT MONO (9000 10775);
DISPLAY INVISIBLE (9000 10775);
FORCEPROP 0 LAST CDS_SEC 1
J 0
(9000 10775);
DISPLAY 1.021277 (9000 10775);
DISPLAY INVISIBLE (9000 10775);
FORCEPROP 1 LASTPIN (8925 10700) $PN 1
J 0
(8937 10712);
DISPLAY 0.787234 (8937 10712);
PAINT MONO (8937 10712);
DISPLAY INVISIBLE (8937 10712);
FORCEPROP 1 LASTPIN (9125 10700) $PN 2
J 0
(9087 10712);
DISPLAY 0.787234 (9087 10712);
PAINT MONO (9087 10712);
DISPLAY INVISIBLE (9087 10712);
FORCEADD Q_CAP..1
R 1
(8975 10800);
FORCEPROP 1 LAST PART_NUMBER CH23906KB14
J 0
(9025 10825);
DISPLAY 0.510638 (9025 10825);
DISPLAY INVISIBLE (9025 10825);
FORCEPROP 2 LAST ROOM NIC1_P12V_MAM_MAM_BOM1
J 0
(9075 10925);
DISPLAY 0.510638 (9075 10925);
FORCEPROP 1 LAST VOLTAGE 50V
J 0
(9075 10875);
DISPLAY 0.510638 (9075 10875);
FORCEPROP 1 LAST VALUE 3900PF
J 0
(8875 10850);
DISPLAY 0.510638 (8875 10850);
FORCEPROP 1 LAST PACK_TYPE C0402
J 0
(8750 10750);
DISPLAY 0.510638 (8750 10750);
FORCEPROP 1 LAST $LOCATION PC4056
J 0
(8725 10800);
DISPLAY 0.510638 (8725 10800);
FORCEPROP 2 LAST ROOM1 NIC1_P12V_MAM_TIC_BOM2
J 0
(9075 10975);
DISPLAY 1.021277 (9075 10975);
DISPLAY INVISIBLE (9075 10975);
FORCEPROP 2 LAST CDS_LIB pure_quanta
R 1
J 0
(8975 10800);
DISPLAY INVISIBLE (8975 10800);
FORCEPROP 1 LAST TOLERANCE 10%
R 1
J 0
(9025 10850);
DISPLAY 0.638298 (9025 10850);
DISPLAY INVISIBLE (9025 10850);
FORCEPROP 1 LAST MATERIAL EMPTY
R 1
J 0
(8975 10850);
DISPLAY 0.638298 (8975 10850);
DISPLAY INVISIBLE (8975 10850);
FORCEPROP 1 LAST PATH I83
R 1
J 0
(8825 10850);
DISPLAY 0.978723 (8825 10850);
PAINT WHITE (8825 10850);
DISPLAY INVISIBLE (8825 10850);
FORCEPROP 0 LAST CDS_LOCATION PC4056
R 1
J 0
(9075 10925);
DISPLAY 1.021277 (9075 10925);
DISPLAY INVISIBLE (9075 10925);
FORCEPROP 0 LAST $SEC 1
R 1
J 0
(9075 10925);
DISPLAY 0.680851 (9075 10925);
PAINT MONO (9075 10925);
DISPLAY INVISIBLE (9075 10925);
FORCEPROP 0 LAST CDS_SEC 1
R 1
J 0
(9075 10925);
DISPLAY 1.021277 (9075 10925);
DISPLAY INVISIBLE (9075 10925);
FORCEPROP 1 LASTPIN (8875 10800) $PN 1
R 1
J 0
(8895 10810);
DISPLAY 0.787234 (8895 10810);
PAINT MONO (8895 10810);
DISPLAY INVISIBLE (8895 10810);
FORCEPROP 1 LASTPIN (9075 10800) $PN 2
R 1
J 0
(9095 10810);
DISPLAY 0.787234 (9095 10810);
PAINT MONO (9095 10810);
DISPLAY INVISIBLE (9095 10810);
FORCEADD Q_RES..2
(8625 11025);
FORCEPROP 1 LAST PART_NUMBER CS61002FB02
J 0
(8665 10900);
DISPLAY 0.510638 (8665 10900);
DISPLAY INVISIBLE (8665 10900);
FORCEPROP 1 LAST WATTAGE 1/16W
J 0
(8665 11000);
DISPLAY 0.510638 (8665 11000);
FORCEPROP 2 LAST ROOM NIC1_P12V_MAM_MAM_BOM1
J 0
(8675 11200);
DISPLAY 0.510638 (8675 11200);
FORCEPROP 1 LAST VALUE 10M
J 0
(8670 11100);
DISPLAY 0.510638 (8670 11100);
FORCEPROP 1 LAST TOLERANCE 1%
J 0
(8670 11050);
DISPLAY 0.510638 (8670 11050);
FORCEPROP 1 LAST MATERIAL EMPTY
J 0
(8665 10950);
DISPLAY 0.510638 (8665 10950);
PAINT RED (8665 10950);
FORCEPROP 1 LAST PACK_TYPE 0402LF
J 0
(8665 10850);
DISPLAY 0.510638 (8665 10850);
FORCEPROP 1 LAST LOCATION PR4524
J 0
(8670 11150);
DISPLAY 0.510638 (8670 11150);
FORCEPROP 1 LASTPIN (8625 11125) $PN 1
J 0
(8630 11087);
DISPLAY 0.510638 (8630 11087);
PAINT MONO (8630 11087);
FORCEPROP 1 LASTPIN (8625 10925) $PN 2
J 0
(8630 10935);
DISPLAY 0.510638 (8630 10935);
PAINT MONO (8630 10935);
FORCEPROP 2 LAST ROOM1 NIC1_P12V_MAM_TIC_BOM2
J 0
(8675 11250);
DISPLAY 1.021277 (8675 11250);
DISPLAY INVISIBLE (8675 11250);
FORCEPROP 2 LAST CDS_LIB pure_quanta
J 0
(8625 11025);
DISPLAY INVISIBLE (8625 11025);
FORCEPROP 1 LAST PATH I84
J 0
(8675 11200);
DISPLAY 0.978723 (8675 11200);
PAINT WHITE (8675 11200);
DISPLAY INVISIBLE (8675 11200);
FORCEPROP 0 LAST $SEC 1
J 0
(8675 11200);
DISPLAY 0.680851 (8675 11200);
PAINT MONO (8675 11200);
DISPLAY INVISIBLE (8675 11200);
FORCEPROP 0 LAST CDS_SEC 1
J 0
(8675 11200);
DISPLAY 1.021277 (8675 11200);
DISPLAY INVISIBLE (8675 11200);
FORCEADD GND..1
(8475 12125);
FORCEPROP 3 LASTPIN (8475 12175) SIG_NAME GND\g
J 0
(8485 12185);
DISPLAY 0.659574 (8485 12185);
PAINT MONO (8485 12185);
DISPLAY INVISIBLE (8485 12185);
FORCEPROP 2 LAST CDS_LIB logical_power
J 0
(8475 12125);
DISPLAY INVISIBLE (8475 12125);
FORCEPROP 1 LAST HDL_POWER GND
J 0
(8475 12275);
DISPLAY 0.872340 (8475 12275);
PAINT GREEN (8475 12275);
DISPLAY INVISIBLE (8475 12275);
FORCEPROP 1 LAST SIZE 1B
J 0
(8550 12075);
DISPLAY 0.872340 (8550 12075);
PAINT GREEN (8550 12075);
DISPLAY INVISIBLE (8550 12075);
FORCEPROP 1 LAST PATH I85
J 0
(8550 12125);
DISPLAY 0.872340 (8550 12125);
PAINT AQUA (8550 12125);
DISPLAY INVISIBLE (8550 12125);
FORCEADD SCHOTTKY_AC..1
R 1
(8725 11675);
FORCEPROP 1 LAST PART_NUMBER BC000340Z30
J 0
(8775 11600);
DISPLAY 0.510638 (8775 11600);
PAINT GREEN (8775 11600);
DISPLAY INVISIBLE (8775 11600);
FORCEPROP 1 LAST MATERIAL IC
J 0
(8775 11575);
DISPLAY 0.510638 (8775 11575);
PAINT GREEN (8775 11575);
FORCEPROP 2 LAST VALUE B340A-13-F
J 0
(8775 11650);
DISPLAY 0.510638 (8775 11650);
FORCEPROP 1 LAST LOCATION PD102
J 0
(8775 11700);
DISPLAY 0.510638 (8775 11700);
PAINT GREEN (8775 11700);
FORCEPROP 0 LASTPIN (8725 11550) $PN A
R 1
J 2
(8715 11585);
DISPLAY 0.510638 (8715 11585);
FORCEPROP 0 LASTPIN (8725 11800) $PN C
R 1
J 0
(8715 11760);
DISPLAY 0.510638 (8715 11760);
FORCEPROP 0 LAST PART_TYPE SMLF
J 0
(8775 11850);
DISPLAY 1.021277 (8775 11850);
DISPLAY INVISIBLE (8775 11850);
FORCEPROP 1 LAST NEEDS_NO_SIZE TRUE
R 1
J 0
(8775 11750);
DISPLAY 0.468085 (8775 11750);
PAINT GREEN (8775 11750);
DISPLAY INVISIBLE (8775 11750);
FORCEPROP 2 LAST CDS_LIB pure_quanta
R 1
J 0
(8725 11675);
DISPLAY INVISIBLE (8725 11675);
FORCEPROP 1 LAST CDS_LMAN_SYM_OUTLINE -75,50,75,-50
R 1
J 0
(8725 11675);
DISPLAY 0.468085 (8725 11675);
PAINT GREEN (8725 11675);
DISPLAY INVISIBLE (8725 11675);
FORCEPROP 1 LAST PATH I86
R 1
J 0
(8725 11675);
DISPLAY 0.723404 (8725 11675);
PAINT GREEN (8725 11675);
DISPLAY INVISIBLE (8725 11675);
FORCEPROP 0 LAST $SEC 1
R 1
J 0
(8775 11750);
DISPLAY INVISIBLE (8775 11750);
FORCEPROP 0 LAST CDS_SEC 1
R 1
J 0
(8775 11750);
DISPLAY INVISIBLE (8775 11750);
FORCEADD Q_RES..1
(9275 10500);
FORCEPROP 1 LAST PART_NUMBER CS00002JB13
J 0
(9100 10450);
DISPLAY 0.510638 (9100 10450);
DISPLAY INVISIBLE (9100 10450);
FORCEPROP 2 LAST ROOM NIC1_P12V_MAM_MAM_BOM1
J 0
(8975 10575);
DISPLAY 0.510638 (8975 10575);
FORCEPROP 1 LAST PACK_TYPE 0402LF
J 0
(9425 10450);
DISPLAY 0.510638 (9425 10450);
FORCEPROP 1 LAST TOLERANCE 5%
J 0
(9450 10500);
DISPLAY 0.510638 (9450 10500);
FORCEPROP 1 LAST VALUE 0
J 2
(9425 10500);
DISPLAY 0.510638 (9425 10500);
FORCEPROP 1 LAST MATERIAL EMPTY
J 0
(9050 10500);
DISPLAY 0.510638 (9050 10500);
PAINT RED (9050 10500);
FORCEPROP 1 LAST WATTAGE 1/16W
J 2
(9075 10450);
DISPLAY 0.510638 (9075 10450);
FORCEPROP 1 LAST $LOCATION R3869
J 0
(8975 10525);
DISPLAY 0.510638 (8975 10525);
FORCEPROP 1 LASTPIN (9175 10500) $PN 1
J 0
(9187 10512);
DISPLAY 0.510638 (9187 10512);
PAINT MONO (9187 10512);
FORCEPROP 1 LASTPIN (9375 10500) $PN 2
J 0
(9337 10512);
DISPLAY 0.510638 (9337 10512);
PAINT MONO (9337 10512);
FORCEPROP 2 LAST CDS_LIB pure_quanta
J 0
(9275 10500);
DISPLAY INVISIBLE (9275 10500);
FORCEPROP 1 LAST PATH I87
J 0
(9225 10650);
DISPLAY 0.978723 (9225 10650);
PAINT WHITE (9225 10650);
DISPLAY INVISIBLE (9225 10650);
FORCEPROP 0 LAST CDS_LOCATION R3869
J 0
(9225 10600);
DISPLAY 1.021277 (9225 10600);
DISPLAY INVISIBLE (9225 10600);
FORCEPROP 0 LAST $SEC 1
J 0
(9225 10600);
DISPLAY 0.680851 (9225 10600);
PAINT MONO (9225 10600);
DISPLAY INVISIBLE (9225 10600);
FORCEPROP 0 LAST CDS_SEC 1
J 0
(9225 10600);
DISPLAY 1.021277 (9225 10600);
DISPLAY INVISIBLE (9225 10600);
FORCEADD Q_RES..1
(9275 10375);
FORCEPROP 1 LAST PART_NUMBER CS00002JB13
J 0
(9100 10325);
DISPLAY 0.510638 (9100 10325);
DISPLAY INVISIBLE (9100 10325);
FORCEPROP 1 LAST PACK_TYPE 0402LF
J 0
(9425 10325);
DISPLAY 0.510638 (9425 10325);
FORCEPROP 1 LAST TOLERANCE 5%
J 0
(9450 10375);
DISPLAY 0.510638 (9450 10375);
FORCEPROP 1 LAST VALUE 0
J 2
(9425 10375);
DISPLAY 0.510638 (9425 10375);
FORCEPROP 1 LAST MATERIAL EMPTY
J 0
(9050 10375);
DISPLAY 0.510638 (9050 10375);
PAINT RED (9050 10375);
FORCEPROP 1 LAST WATTAGE 1/16W
J 2
(9075 10325);
DISPLAY 0.510638 (9075 10325);
FORCEPROP 0 LAST ROOM1 NIC1_P12V_MAM_TIC_BOM2
J 0
(8975 10225);
DISPLAY 0.510638 (8975 10225);
FORCEPROP 1 LAST $LOCATION R3870
J 0
(8975 10400);
DISPLAY 0.510638 (8975 10400);
FORCEPROP 1 LASTPIN (9175 10375) $PN 1
J 0
(9187 10387);
DISPLAY 0.510638 (9187 10387);
PAINT MONO (9187 10387);
FORCEPROP 1 LASTPIN (9375 10375) $PN 2
J 0
(9337 10387);
DISPLAY 0.510638 (9337 10387);
PAINT MONO (9337 10387);
FORCEPROP 2 LAST CDS_LIB pure_quanta
J 0
(9275 10375);
DISPLAY INVISIBLE (9275 10375);
FORCEPROP 1 LAST PATH I88
J 0
(9225 10525);
DISPLAY 0.978723 (9225 10525);
PAINT WHITE (9225 10525);
DISPLAY INVISIBLE (9225 10525);
FORCEPROP 0 LAST CDS_LOCATION R3870
J 0
(9225 10475);
DISPLAY 1.021277 (9225 10475);
DISPLAY INVISIBLE (9225 10475);
FORCEPROP 0 LAST $SEC 1
J 0
(9225 10475);
DISPLAY 0.680851 (9225 10475);
PAINT MONO (9225 10475);
DISPLAY INVISIBLE (9225 10475);
FORCEPROP 0 LAST CDS_SEC 1
J 0
(9225 10475);
DISPLAY 1.021277 (9225 10475);
DISPLAY INVISIBLE (9225 10475);
FORCEADD GND..1
(9100 10725);
FORCEPROP 3 LASTPIN (9100 10775) SIG_NAME GND\g
J 0
(9110 10785);
DISPLAY 0.659574 (9110 10785);
PAINT MONO (9110 10785);
DISPLAY INVISIBLE (9110 10785);
FORCEPROP 1 LAST HDL_POWER GND
J 0
(9100 10875);
DISPLAY 0.872340 (9100 10875);
PAINT GREEN (9100 10875);
DISPLAY INVISIBLE (9100 10875);
FORCEPROP 2 LAST CDS_LIB logical_power
J 0
(9100 10725);
DISPLAY INVISIBLE (9100 10725);
FORCEPROP 1 LAST SIZE 1B
J 0
(9175 10675);
DISPLAY 0.872340 (9175 10675);
PAINT GREEN (9175 10675);
DISPLAY INVISIBLE (9175 10675);
FORCEPROP 1 LAST PATH I89
J 0
(9175 10725);
DISPLAY 0.872340 (9175 10725);
PAINT AQUA (9175 10725);
DISPLAY INVISIBLE (9175 10725);
FORCEADD MOSFET_NCH_DUAL..1
(3325 10250);
FORCEPROP 1 LAST PART_NUMBER BAM138K0003
J 0
(3476 10164);
DISPLAY 0.510638 (3476 10164);
PAINT GREEN (3476 10164);
DISPLAY INVISIBLE (3476 10164);
FORCEPROP 2 LAST VALUE PJT138K
J 0
(3500 10275);
DISPLAY 0.510638 (3500 10275);
FORCEPROP 2 LAST PART_TYPE SMLF
J 0
(3500 10325);
DISPLAY 0.510638 (3500 10325);
FORCEPROP 2 LAST ROOM NIC1_P12V_MAM_MAM_BOM1
J 0
(3500 10375);
DISPLAY 0.510638 (3500 10375);
FORCEPROP 1 LAST MATERIAL EMPTY
J 0
(3476 10099);
DISPLAY 0.510638 (3476 10099);
PAINT RED (3476 10099);
FORCEPROP 1 LAST $LOCATION Q123
J 0
(3476 10224);
DISPLAY 0.510638 (3476 10224);
PAINT GREEN (3476 10224);
FORCEPROP 0 LASTPIN (3375 10450) $PN 6
R 1
J 0
(3365 10460);
DISPLAY 0.510638 (3365 10460);
PAINT MONO (3365 10460);
FORCEPROP 0 LASTPIN (3125 10200) $PN 2
J 2
(3115 10210);
DISPLAY 0.510638 (3115 10210);
PAINT MONO (3115 10210);
FORCEPROP 0 LASTPIN (3375 10050) $PN 1
R 1
J 2
(3365 10040);
DISPLAY 0.510638 (3365 10040);
PAINT MONO (3365 10040);
FORCEPROP 2 LAST ROOM1 NIC1_P12V_MAM_TIC_BOM2
J 0
(3500 10425);
DISPLAY 1.021277 (3500 10425);
DISPLAY INVISIBLE (3500 10425);
FORCEPROP 1 LAST NEEDS_NO_SIZE TRUE
J 0
(3325 10249);
DISPLAY 0.468085 (3325 10249);
PAINT GREEN (3325 10249);
DISPLAY INVISIBLE (3325 10249);
FORCEPROP 1 LAST CDS_LMAN_SYM_OUTLINE -150,150,150,-150
J 0
(3325 10250);
DISPLAY 0.468085 (3325 10250);
PAINT GREEN (3325 10250);
DISPLAY INVISIBLE (3325 10250);
FORCEPROP 2 LAST CDS_LIB pure_quanta
J 0
(3325 10250);
DISPLAY INVISIBLE (3325 10250);
FORCEPROP 1 LAST PATH I9
J 0
(3325 10250);
DISPLAY 0.723404 (3325 10250);
PAINT GREEN (3325 10250);
DISPLAY INVISIBLE (3325 10250);
FORCEPROP 0 LAST CDS_LOCATION Q123
J 0
(3500 10375);
DISPLAY 1.021277 (3500 10375);
DISPLAY INVISIBLE (3500 10375);
FORCEPROP 0 LAST $SEC 1
J 0
(3500 10375);
DISPLAY 0.680851 (3500 10375);
PAINT MONO (3500 10375);
DISPLAY INVISIBLE (3500 10375);
FORCEPROP 0 LAST CDS_SEC 1
J 0
(3500 10375);
DISPLAY 1.021277 (3500 10375);
DISPLAY INVISIBLE (3500 10375);
FORCEADD Q_RES..2
(9375 10975);
FORCEPROP 1 LAST PART_NUMBER CS41002FB09
J 0
(9415 10850);
DISPLAY 0.510638 (9415 10850);
DISPLAY INVISIBLE (9415 10850);
FORCEPROP 1 LAST PACK_TYPE 0402LF
J 0
(9415 10800);
DISPLAY 0.510638 (9415 10800);
FORCEPROP 1 LAST MATERIAL EMPTY
J 0
(9415 10900);
DISPLAY 0.510638 (9415 10900);
PAINT RED (9415 10900);
FORCEPROP 1 LAST WATTAGE 1/16W
J 0
(9415 10950);
DISPLAY 0.510638 (9415 10950);
FORCEPROP 2 LAST ROOM NIC1_P12V_MAM_MAM_BOM1
J 0
(9425 11150);
DISPLAY 0.510638 (9425 11150);
FORCEPROP 1 LAST VALUE 100K
J 0
(9420 11050);
DISPLAY 0.510638 (9420 11050);
FORCEPROP 1 LAST TOLERANCE 1%
J 0
(9420 11000);
DISPLAY 0.510638 (9420 11000);
FORCEPROP 1 LAST LOCATION R3799
J 0
(9420 11100);
DISPLAY 0.510638 (9420 11100);
FORCEPROP 1 LASTPIN (9375 11075) $PN 1
J 0
(9380 11037);
DISPLAY 0.510638 (9380 11037);
PAINT MONO (9380 11037);
FORCEPROP 1 LASTPIN (9375 10875) $PN 2
J 0
(9380 10885);
DISPLAY 0.510638 (9380 10885);
PAINT MONO (9380 10885);
FORCEPROP 2 LAST ROOM1 NIC1_P12V_MAM_TIC_BOM2
J 0
(9425 11200);
DISPLAY 1.021277 (9425 11200);
DISPLAY INVISIBLE (9425 11200);
FORCEPROP 2 LAST CDS_LIB pure_quanta
J 0
(9375 10975);
DISPLAY INVISIBLE (9375 10975);
FORCEPROP 1 LAST PATH I90
J 0
(9425 11150);
DISPLAY 0.978723 (9425 11150);
PAINT WHITE (9425 11150);
DISPLAY INVISIBLE (9425 11150);
FORCEPROP 0 LAST $SEC 1
J 0
(9425 11150);
DISPLAY 0.680851 (9425 11150);
PAINT MONO (9425 11150);
DISPLAY INVISIBLE (9425 11150);
FORCEPROP 0 LAST CDS_SEC 1
J 0
(9425 11150);
DISPLAY 1.021277 (9425 11150);
DISPLAY INVISIBLE (9425 11150);
FORCEADD VCCAUX15..1
(9550 11275);
FORCEPROP 3 LASTPIN (9550 11225) SIG_NAME P3V3_AUX\g
J 0
(9560 11235);
DISPLAY 0.659574 (9560 11235);
PAINT MONO (9560 11235);
DISPLAY INVISIBLE (9560 11235);
FORCEPROP 1 LAST HDL_POWER P3V3_AUX
J 1
(9550 11325);
DISPLAY 0.510638 (9550 11325);
PAINT GREEN (9550 11325);
FORCEPROP 2 LAST CDS_LIB logical_power
J 0
(9550 11275);
DISPLAY INVISIBLE (9550 11275);
FORCEPROP 1 LAST PATH I91
J 0
(9600 11300);
DISPLAY 0.872340 (9600 11300);
PAINT AQUA (9600 11300);
DISPLAY INVISIBLE (9600 11300);
FORCEADD Q_RES..2
(9800 10975);
FORCEPROP 1 LAST PART_NUMBER CS41002FB09
J 0
(9840 10850);
DISPLAY 0.510638 (9840 10850);
DISPLAY INVISIBLE (9840 10850);
FORCEPROP 1 LAST VALUE 100K
J 0
(9845 11050);
DISPLAY 0.510638 (9845 11050);
FORCEPROP 2 LAST ROOM NIC1_P12V_MAM_MAM_BOM1
J 0
(9850 11150);
DISPLAY 0.510638 (9850 11150);
FORCEPROP 1 LAST TOLERANCE 1%
J 0
(9845 11000);
DISPLAY 0.510638 (9845 11000);
FORCEPROP 1 LAST MATERIAL EMPTY
J 0
(9840 10900);
DISPLAY 0.510638 (9840 10900);
PAINT RED (9840 10900);
FORCEPROP 1 LAST WATTAGE 1/16W
J 0
(9840 10950);
DISPLAY 0.510638 (9840 10950);
FORCEPROP 1 LAST PACK_TYPE 0402LF
J 0
(9840 10800);
DISPLAY 0.510638 (9840 10800);
FORCEPROP 1 LAST LOCATION R3797
J 0
(9845 11100);
DISPLAY 0.510638 (9845 11100);
FORCEPROP 1 LASTPIN (9800 11075) $PN 1
J 0
(9805 11037);
DISPLAY 0.510638 (9805 11037);
PAINT MONO (9805 11037);
FORCEPROP 1 LASTPIN (9800 10875) $PN 2
J 0
(9805 10885);
DISPLAY 0.510638 (9805 10885);
PAINT MONO (9805 10885);
FORCEPROP 2 LAST ROOM1 NIC1_P12V_MAM_TIC_BOM2
J 0
(9850 11200);
DISPLAY 1.021277 (9850 11200);
DISPLAY INVISIBLE (9850 11200);
FORCEPROP 2 LAST CDS_LIB pure_quanta
J 0
(9800 10975);
DISPLAY INVISIBLE (9800 10975);
FORCEPROP 1 LAST PATH I92
J 0
(9850 11150);
DISPLAY 0.978723 (9850 11150);
PAINT WHITE (9850 11150);
DISPLAY INVISIBLE (9850 11150);
FORCEPROP 0 LAST $SEC 1
J 0
(9850 11150);
DISPLAY 0.680851 (9850 11150);
PAINT MONO (9850 11150);
DISPLAY INVISIBLE (9850 11150);
FORCEPROP 0 LAST CDS_SEC 1
J 0
(9850 11150);
DISPLAY 1.021277 (9850 11150);
DISPLAY INVISIBLE (9850 11150);
FORCEADD Q_CAP..1
(9200 11650);
FORCEPROP 1 LAST PART_NUMBER CH4104K1B00
J 0
(9250 11500);
DISPLAY 0.510638 (9250 11500);
DISPLAY INVISIBLE (9250 11500);
FORCEPROP 1 LAST PACK_TYPE 0402
J 0
(9250 11550);
DISPLAY 0.510638 (9250 11550);
FORCEPROP 1 LAST MATERIAL X7R
J 0
(9250 11600);
DISPLAY 0.510638 (9250 11600);
FORCEPROP 1 LAST VOLTAGE 25V
J 0
(9250 11650);
DISPLAY 0.510638 (9250 11650);
FORCEPROP 1 LAST VALUE 0.1UF
J 0
(9250 11700);
DISPLAY 0.510638 (9250 11700);
FORCEPROP 1 LAST LOCATION PC2092
J 0
(9250 11750);
DISPLAY 0.510638 (9250 11750);
FORCEPROP 1 LAST TOLERANCE 10%
J 0
(9250 11600);
DISPLAY 0.978723 (9250 11600);
DISPLAY INVISIBLE (9250 11600);
FORCEPROP 2 LAST CDS_LIB pure_quanta
J 0
(9200 11650);
DISPLAY INVISIBLE (9200 11650);
FORCEPROP 1 LAST PATH I93
J 0
(9250 11800);
DISPLAY 0.978723 (9250 11800);
PAINT WHITE (9250 11800);
DISPLAY INVISIBLE (9250 11800);
FORCEPROP 0 LAST $SEC 1
J 0
(9250 11800);
DISPLAY 0.680851 (9250 11800);
PAINT MONO (9250 11800);
DISPLAY INVISIBLE (9250 11800);
FORCEPROP 0 LAST CDS_SEC 1
J 0
(9250 11800);
DISPLAY 1.021277 (9250 11800);
DISPLAY INVISIBLE (9250 11800);
FORCEPROP 1 LASTPIN (9200 11750) $PN 1
J 0
(9210 11730);
DISPLAY 0.787234 (9210 11730);
PAINT MONO (9210 11730);
DISPLAY INVISIBLE (9210 11730);
FORCEPROP 1 LASTPIN (9200 11550) $PN 2
J 0
(9210 11530);
DISPLAY 0.787234 (9210 11530);
PAINT MONO (9210 11530);
DISPLAY INVISIBLE (9210 11530);
FORCEADD Q_CAP..1
(9625 11650);
FORCEPROP 1 LAST PART_NUMBER CH6223MEA03
J 0
(9675 11500);
DISPLAY 0.510638 (9675 11500);
DISPLAY INVISIBLE (9675 11500);
FORCEPROP 1 LAST MATERIAL X6S
J 0
(9675 11600);
DISPLAY 0.510638 (9675 11600);
FORCEPROP 1 LAST PACK_TYPE C0805
J 0
(9675 11550);
DISPLAY 0.510638 (9675 11550);
FORCEPROP 1 LAST VALUE 22UF
J 0
(9675 11700);
DISPLAY 0.510638 (9675 11700);
FORCEPROP 1 LAST VOLTAGE 16V
J 0
(9675 11650);
DISPLAY 0.510638 (9675 11650);
FORCEPROP 1 LAST LOCATION PC2080
J 0
(9675 11750);
DISPLAY 0.510638 (9675 11750);
FORCEPROP 1 LAST TOLERANCE 20%
J 0
(9675 11600);
DISPLAY 0.978723 (9675 11600);
DISPLAY INVISIBLE (9675 11600);
FORCEPROP 2 LAST CDS_LIB pure_quanta
J 0
(9625 11650);
DISPLAY INVISIBLE (9625 11650);
FORCEPROP 1 LAST PATH I94
J 0
(9675 11800);
DISPLAY 0.978723 (9675 11800);
PAINT WHITE (9675 11800);
DISPLAY INVISIBLE (9675 11800);
FORCEPROP 0 LAST $SEC 1
J 0
(9675 11800);
DISPLAY INVISIBLE (9675 11800);
FORCEPROP 0 LAST CDS_SEC 1
J 0
(9675 11800);
DISPLAY INVISIBLE (9675 11800);
FORCEPROP 1 LASTPIN (9625 11750) $PN 1
J 0
(9635 11730);
DISPLAY 0.787234 (9635 11730);
PAINT MONO (9635 11730);
DISPLAY INVISIBLE (9635 11730);
FORCEPROP 1 LASTPIN (9625 11550) $PN 2
J 0
(9635 11530);
DISPLAY 0.787234 (9635 11530);
PAINT MONO (9635 11530);
DISPLAY INVISIBLE (9635 11530);
FORCEADD GND..1
(10025 11300);
FORCEPROP 3 LASTPIN (10025 11350) SIG_NAME GND\g
J 0
(10035 11360);
DISPLAY 0.659574 (10035 11360);
PAINT MONO (10035 11360);
DISPLAY INVISIBLE (10035 11360);
FORCEPROP 1 LAST HDL_POWER GND
J 0
(10025 11450);
DISPLAY 0.872340 (10025 11450);
PAINT GREEN (10025 11450);
DISPLAY INVISIBLE (10025 11450);
FORCEPROP 1 LAST SIZE 1B
J 0
(10100 11250);
DISPLAY 0.872340 (10100 11250);
PAINT GREEN (10100 11250);
DISPLAY INVISIBLE (10100 11250);
FORCEPROP 2 LAST CDS_LIB logical_power
J 0
(10025 11300);
DISPLAY INVISIBLE (10025 11300);
FORCEPROP 1 LAST PATH I95
J 0
(10100 11300);
DISPLAY 0.872340 (10100 11300);
PAINT AQUA (10100 11300);
DISPLAY INVISIBLE (10100 11300);
FORCEADD Q_CAP..1
(10025 11650);
FORCEPROP 1 LAST PART_NUMBER CH6103KEA03
J 0
(10075 11500);
DISPLAY 0.510638 (10075 11500);
DISPLAY INVISIBLE (10075 11500);
FORCEPROP 1 LAST PACK_TYPE C0805
J 0
(10075 11550);
DISPLAY 0.510638 (10075 11550);
FORCEPROP 1 LAST MATERIAL X6S
J 0
(10075 11600);
DISPLAY 0.510638 (10075 11600);
FORCEPROP 1 LAST VOLTAGE 16V
J 0
(10075 11650);
DISPLAY 0.510638 (10075 11650);
FORCEPROP 1 LAST VALUE 10UF
J 0
(10075 11700);
DISPLAY 0.510638 (10075 11700);
FORCEPROP 1 LAST LOCATION PC2082
J 0
(10075 11750);
DISPLAY 0.510638 (10075 11750);
FORCEPROP 1 LAST TOLERANCE 10%
J 0
(9814 11610);
DISPLAY 0.787234 (9814 11610);
PAINT GREEN (9814 11610);
DISPLAY INVISIBLE (9814 11610);
FORCEPROP 2 LAST CDS_LIB pure_quanta
J 0
(10025 11650);
DISPLAY INVISIBLE (10025 11650);
FORCEPROP 1 LAST PATH I96
J 0
(10075 11800);
DISPLAY 0.978723 (10075 11800);
PAINT WHITE (10075 11800);
DISPLAY INVISIBLE (10075 11800);
FORCEPROP 0 LAST $SEC 1
J 0
(10075 11800);
DISPLAY INVISIBLE (10075 11800);
FORCEPROP 0 LAST CDS_SEC 1
J 0
(10075 11800);
DISPLAY INVISIBLE (10075 11800);
FORCEPROP 1 LASTPIN (10025 11750) $PN 1
J 0
(10035 11730);
DISPLAY 0.787234 (10035 11730);
PAINT MONO (10035 11730);
DISPLAY INVISIBLE (10035 11730);
FORCEPROP 1 LASTPIN (10025 11550) $PN 2
J 0
(10035 11530);
DISPLAY 0.787234 (10035 11530);
PAINT MONO (10035 11530);
DISPLAY INVISIBLE (10035 11530);
FORCEADD UNIVERSAL_POWER..1
R 2
(10025 11950);
FORCEPROP 3 LASTPIN (10025 11900) SIG_NAME P12V_OCP_SFF\g
J 0
(10035 11910);
DISPLAY 0.659574 (10035 11910);
PAINT MONO (10035 11910);
DISPLAY INVISIBLE (10035 11910);
FORCEPROP 1 LAST HDL_POWER P12V_OCP_SFF
J 1
(10025 12000);
DISPLAY 0.510638 (10025 12000);
PAINT GREEN (10025 12000);
FORCEPROP 2 LAST CDS_LIB logical_power
J 0
(10025 11950);
DISPLAY INVISIBLE (10025 11950);
FORCEPROP 1 LAST PATH I97
J 2
(9975 11975);
DISPLAY 0.872340 (9975 11975);
PAINT AQUA (9975 11975);
DISPLAY INVISIBLE (9975 11975);
FORCEADD OFFPAGE..2
(10275 10700);
PAINT AQUA (10275 10700);
FORCEPROP 2 LAST $XR2 214 
J 0
(10704 10700);
DISPLAY 0.638298 (10704 10700);
PAINT MONO (10704 10700);
FORCEPROP 2 LAST $XR1 158 
J 0
(10584 10700);
DISPLAY 0.638298 (10584 10700);
PAINT MONO (10584 10700);
FORCEPROP 2 LAST $XR0 157 
J 0
(10464 10700);
DISPLAY 0.638298 (10464 10700);
PAINT MONO (10464 10700);
FORCEPROP 1 LAST COMMENT_BODY TRUE
J 0
(10230 10605);
DISPLAY 0.872340 (10230 10605);
PAINT GREEN (10230 10605);
DISPLAY INVISIBLE (10230 10605);
FORCEPROP 1 LAST OFFPAGE TRUE
J 0
(10600 10575);
DISPLAY 0.872340 (10600 10575);
PAINT AQUA (10600 10575);
DISPLAY INVISIBLE (10600 10575);
FORCEPROP 2 LAST CDS_LIB standard
J 0
(10275 10700);
DISPLAY INVISIBLE (10275 10700);
FORCEPROP 2 LAST PATH I98
J 0
(10600 10725);
DISPLAY 1.021277 (10600 10725);
DISPLAY INVISIBLE (10600 10725);
FORCEADD OFFPAGE..2
(10525 10500);
PAINT AQUA (10525 10500);
FORCEPROP 2 LAST $XR0 250 
J 0
(10714 10500);
DISPLAY 0.638298 (10714 10500);
PAINT MONO (10714 10500);
FORCEPROP 1 LAST COMMENT_BODY TRUE
J 0
(10480 10405);
DISPLAY 0.872340 (10480 10405);
PAINT GREEN (10480 10405);
DISPLAY INVISIBLE (10480 10405);
FORCEPROP 1 LAST OFFPAGE TRUE
J 0
(10850 10375);
DISPLAY 0.872340 (10850 10375);
PAINT AQUA (10850 10375);
DISPLAY INVISIBLE (10850 10375);
FORCEPROP 2 LAST CDS_LIB standard
J 0
(10525 10500);
DISPLAY INVISIBLE (10525 10500);
FORCEPROP 2 LAST PATH I99
J 0
(10725 10525);
DISPLAY 1.021277 (10725 10525);
DISPLAY INVISIBLE (10725 10525);
FORCEADD QUANTA_TITLE_BLOCK_C..1
(10825 7825);
FORCEPROP 0 LAST CDS_CON_LAST_MODIFIED Fri Aug 25 14:02:21 2023
J 0
(8940 7840);
PAINT MONO (8940 7840);
DISPLAY INVISIBLE (8940 7840);
FORCEPROP 2 LAST CUSTOM_TXT_CDS <XR_PAGE_TITLE>
J 0
(2935 13075);
DISPLAY 0.638298 (2935 13075);
PAINT PINK (2935 13075);
DISPLAY INVISIBLE (2935 13075);
FORCEPROP 2 LAST CUSTOM_TXT_CDS <CON_LAST_MODIFIED>
J 0
(8940 7840);
DISPLAY 0.978723 (8940 7840);
FORCEPROP 2 LAST CUSTOM_TXT_CDS <CON_PAGE_NUM> OF <CON_TOTAL_PAGES>
J 0
(10379 7843);
DISPLAY 0.978723 (10379 7843);
FORCEPROP 2 LAST CUSTOM_TXT_CDS <Q_REV>
J 0
(10641 7928);
DISPLAY 1.212766 (10641 7928);
FORCEPROP 2 LAST CUSTOM_TXT_CDS <Q_PROJ>
J 0
(8443 7927);
DISPLAY 1.212766 (8443 7927);
FORCEPROP 2 LAST CUSTOM_TXT_CDS <Q_NUMBER>
J 0
(9422 7928);
DISPLAY 1.212766 (9422 7928);
FORCEPROP 2 LAST CUSTOM_TXT_CDS <NAME_1>
J 0
(7650 8000);
FORCEPROP 2 LAST CUSTOM_TXT_CDS <NAME_2>
J 0
(7650 7875);
FORCEPROP 1 LAST Q_TITLE SFF_OCP3.0 HSC(1/3)
J 0
(1575 7900);
DISPLAY 2.446809 (1575 7900);
PAINT GREEN (1575 7900);
FORCEPROP 1 LAST Q_DEPT 
J 1
(7062 7874);
DISPLAY 1.957447 (7062 7874);
PAINT GREEN (7062 7874);
FORCEPROP 2 LAST CDS_XR_PAGE_TITLE CR-156 : @S9S_MB_2U_LIB.S9S_MB_2U(SCH_1):PAGE156
J 0
(2935 13075);
DISPLAY 0.638298 (2935 13075);
PAINT PINK (2935 13075);
DISPLAY INVISIBLE (2935 13075);
FORCEPROP 2 LAST PAGE_BORDER TRUE
J 0
(2935 13075);
DISPLAY 0.638298 (2935 13075);
PAINT PINK (2935 13075);
DISPLAY INVISIBLE (2935 13075);
FORCEPROP 1 LAST COMMENT_BODY TRUE
J 0
(10837 7812);
DISPLAY 0.978723 (10837 7812);
PAINT GREEN (10837 7812);
DISPLAY INVISIBLE (10837 7812);
FORCEPROP 1 LAST CDS_LMAN_SYM_OUTLINE -9475,6775,100,-125
J 0
(10825 7825);
DISPLAY 0.468085 (10825 7825);
PAINT GREEN (10825 7825);
DISPLAY INVISIBLE (10825 7825);
FORCEPROP 2 LAST CDS_LIB pure_quanta
J 0
(10825 7825);
PAINT MONO (10825 7825);
DISPLAY INVISIBLE (10825 7825);
FORCEADD DNS..2
(2450 10175);
PAINT RED (2450 10175);
FORCEPROP 1 LAST COMMENT_BODY TRUE
R 1
J 0
(2525 9950);
DISPLAY 0.872340 (2525 9950);
PAINT GREEN (2525 9950);
DISPLAY INVISIBLE (2525 9950);
FORCEPROP 2 LAST CDS_LIB mstr_misc
J 0
(2450 10175);
DISPLAY INVISIBLE (2450 10175);
FORCEADD DNS..2
(3375 10250);
PAINT RED (3375 10250);
FORCEPROP 1 LAST COMMENT_BODY TRUE
R 1
J 0
(3450 10025);
DISPLAY 0.872340 (3450 10025);
PAINT GREEN (3450 10025);
DISPLAY INVISIBLE (3450 10025);
FORCEPROP 2 LAST CDS_LIB mstr_misc
J 0
(3375 10250);
DISPLAY INVISIBLE (3375 10250);
FORCEADD DNS..2
(3400 10850);
PAINT RED (3400 10850);
FORCEPROP 1 LAST COMMENT_BODY TRUE
R 1
J 0
(3475 10625);
DISPLAY 0.872340 (3475 10625);
PAINT GREEN (3475 10625);
DISPLAY INVISIBLE (3475 10625);
FORCEPROP 2 LAST CDS_LIB mstr_misc
J 0
(3400 10850);
DISPLAY INVISIBLE (3400 10850);
FORCEADD DNS..2
(5950 10175);
PAINT RED (5950 10175);
FORCEPROP 1 LAST COMMENT_BODY TRUE
R 1
J 0
(6025 9950);
DISPLAY 0.872340 (6025 9950);
PAINT GREEN (6025 9950);
DISPLAY INVISIBLE (6025 9950);
FORCEPROP 2 LAST CDS_LIB mstr_misc
J 0
(5950 10175);
DISPLAY INVISIBLE (5950 10175);
FORCEADD DNS..2
(4100 10600);
PAINT RED (4100 10600);
FORCEPROP 1 LAST COMMENT_BODY TRUE
R 1
J 0
(4175 10375);
DISPLAY 0.872340 (4175 10375);
PAINT GREEN (4175 10375);
DISPLAY INVISIBLE (4175 10375);
FORCEPROP 2 LAST CDS_LIB mstr_misc
J 0
(4100 10600);
DISPLAY INVISIBLE (4100 10600);
FORCEADD DNS..2
(5425 10875);
PAINT RED (5425 10875);
FORCEPROP 2 LAST CDS_LIB mstr_misc
J 0
(5425 10875);
DISPLAY INVISIBLE (5425 10875);
FORCEPROP 1 LAST COMMENT_BODY TRUE
R 1
J 0
(5500 10650);
DISPLAY 0.872340 (5500 10650);
PAINT GREEN (5500 10650);
DISPLAY INVISIBLE (5500 10650);
FORCEADD DNS..2
(5950 10450);
PAINT RED (5950 10450);
FORCEPROP 1 LAST COMMENT_BODY TRUE
R 1
J 0
(6025 10225);
DISPLAY 0.872340 (6025 10225);
PAINT GREEN (6025 10225);
DISPLAY INVISIBLE (6025 10225);
FORCEPROP 2 LAST CDS_LIB mstr_misc
J 0
(5950 10450);
DISPLAY INVISIBLE (5950 10450);
FORCEADD DNS..2
(5950 11125);
PAINT RED (5950 11125);
FORCEPROP 1 LAST COMMENT_BODY TRUE
R 1
J 0
(6025 10900);
DISPLAY 0.872340 (6025 10900);
PAINT GREEN (6025 10900);
DISPLAY INVISIBLE (6025 10900);
FORCEPROP 2 LAST CDS_LIB mstr_misc
J 0
(5950 11125);
DISPLAY INVISIBLE (5950 11125);
FORCEADD DNS..2
(6475 10725);
PAINT RED (6475 10725);
FORCEPROP 1 LAST COMMENT_BODY TRUE
R 1
J 0
(6550 10500);
DISPLAY 0.872340 (6550 10500);
PAINT GREEN (6550 10500);
DISPLAY INVISIBLE (6550 10500);
FORCEPROP 2 LAST CDS_LIB mstr_misc
J 0
(6475 10725);
DISPLAY INVISIBLE (6475 10725);
FORCEADD DNS..2
(6250 11025);
PAINT RED (6250 11025);
FORCEPROP 1 LAST COMMENT_BODY TRUE
R 1
J 0
(6325 10800);
DISPLAY 0.872340 (6325 10800);
PAINT GREEN (6325 10800);
DISPLAY INVISIBLE (6325 10800);
FORCEPROP 2 LAST CDS_LIB mstr_misc
J 0
(6250 11025);
DISPLAY INVISIBLE (6250 11025);
FORCEADD DNS..2
(6275 11425);
PAINT RED (6275 11425);
FORCEPROP 1 LAST COMMENT_BODY TRUE
R 1
J 0
(6350 11200);
DISPLAY 0.872340 (6350 11200);
PAINT GREEN (6350 11200);
DISPLAY INVISIBLE (6350 11200);
FORCEPROP 2 LAST CDS_LIB mstr_misc
J 0
(6275 11425);
DISPLAY INVISIBLE (6275 11425);
FORCEADD DNS..2
(7525 10825);
PAINT RED (7525 10825);
FORCEPROP 1 LAST COMMENT_BODY TRUE
R 1
J 0
(7600 10600);
DISPLAY 0.872340 (7600 10600);
PAINT GREEN (7600 10600);
DISPLAY INVISIBLE (7600 10600);
FORCEPROP 2 LAST CDS_LIB mstr_misc
J 0
(7525 10825);
DISPLAY INVISIBLE (7525 10825);
FORCEADD DNS..2
(8400 10300);
PAINT RED (8400 10300);
FORCEPROP 1 LAST COMMENT_BODY TRUE
R 1
J 0
(8475 10075);
DISPLAY 0.872340 (8475 10075);
PAINT GREEN (8475 10075);
DISPLAY INVISIBLE (8475 10075);
FORCEPROP 2 LAST CDS_LIB mstr_misc
J 0
(8400 10300);
DISPLAY INVISIBLE (8400 10300);
FORCEADD CAD_NOTE..1
(9225 10125);
FORCEPROP 0 LAST S1 R3869/R3870 CO-LAYOUT
J 0
(9100 10000);
DISPLAY 0.808511 (9100 10000);
PAINT WHITE (9100 10000);
FORCEPROP 1 LAST COMMENT_BODY TRUE
J 0
(9250 10225);
DISPLAY 0.978723 (9250 10225);
DISPLAY INVISIBLE (9250 10225);
FORCEPROP 2 LAST CDS_LIB logical_power
J 0
(9225 10125);
DISPLAY INVISIBLE (9225 10125);
FORCEADD DNS..2
(8325 11025);
PAINT RED (8325 11025);
FORCEPROP 1 LAST COMMENT_BODY TRUE
R 1
J 0
(8400 10800);
DISPLAY 0.872340 (8400 10800);
PAINT GREEN (8400 10800);
DISPLAY INVISIBLE (8400 10800);
FORCEPROP 2 LAST CDS_LIB mstr_misc
J 0
(8325 11025);
DISPLAY INVISIBLE (8325 11025);
FORCEADD DNS..2
(8650 11000);
PAINT RED (8650 11000);
FORCEPROP 1 LAST COMMENT_BODY TRUE
R 1
J 0
(8725 10775);
DISPLAY 0.872340 (8725 10775);
PAINT GREEN (8725 10775);
DISPLAY INVISIBLE (8725 10775);
FORCEPROP 2 LAST CDS_LIB mstr_misc
J 0
(8650 11000);
DISPLAY INVISIBLE (8650 11000);
FORCEADD DNS..2
(8975 10825);
PAINT RED (8975 10825);
FORCEPROP 1 LAST COMMENT_BODY TRUE
R 1
J 0
(9050 10600);
DISPLAY 0.872340 (9050 10600);
PAINT GREEN (9050 10600);
DISPLAY INVISIBLE (9050 10600);
FORCEPROP 2 LAST CDS_LIB mstr_misc
J 0
(8975 10825);
DISPLAY INVISIBLE (8975 10825);
FORCEADD DNS..2
(9025 10725);
PAINT RED (9025 10725);
FORCEPROP 1 LAST COMMENT_BODY TRUE
R 1
J 0
(9100 10500);
DISPLAY 0.872340 (9100 10500);
PAINT GREEN (9100 10500);
DISPLAY INVISIBLE (9100 10500);
FORCEPROP 2 LAST CDS_LIB mstr_misc
J 0
(9025 10725);
DISPLAY INVISIBLE (9025 10725);
FORCEADD DNS..2
(9275 10400);
PAINT RED (9275 10400);
FORCEPROP 1 LAST COMMENT_BODY TRUE
R 1
J 0
(9350 10175);
DISPLAY 0.872340 (9350 10175);
PAINT GREEN (9350 10175);
DISPLAY INVISIBLE (9350 10175);
FORCEPROP 2 LAST CDS_LIB mstr_misc
J 0
(9275 10400);
DISPLAY INVISIBLE (9275 10400);
FORCEADD DNS..2
(9300 10500);
PAINT RED (9300 10500);
FORCEPROP 1 LAST COMMENT_BODY TRUE
R 1
J 0
(9375 10275);
DISPLAY 0.872340 (9375 10275);
PAINT GREEN (9375 10275);
DISPLAY INVISIBLE (9375 10275);
FORCEPROP 2 LAST CDS_LIB mstr_misc
J 0
(9300 10500);
DISPLAY INVISIBLE (9300 10500);
FORCEADD DNS..2
(9375 11000);
PAINT RED (9375 11000);
FORCEPROP 1 LAST COMMENT_BODY TRUE
R 1
J 0
(9450 10775);
DISPLAY 0.872340 (9450 10775);
PAINT GREEN (9450 10775);
DISPLAY INVISIBLE (9450 10775);
FORCEPROP 2 LAST CDS_LIB mstr_misc
J 0
(9375 11000);
DISPLAY INVISIBLE (9375 11000);
FORCEADD DNS..2
(9800 11000);
PAINT RED (9800 11000);
FORCEPROP 1 LAST COMMENT_BODY TRUE
R 1
J 0
(9875 10775);
DISPLAY 0.872340 (9875 10775);
PAINT GREEN (9875 10775);
DISPLAY INVISIBLE (9875 10775);
FORCEPROP 2 LAST CDS_LIB mstr_misc
J 0
(9800 11000);
DISPLAY INVISIBLE (9800 11000);
FORCEADD DNS..2
(8600 13125);
PAINT RED (8600 13125);
FORCEPROP 2 LAST CDS_LIB mstr_misc
J 0
(8600 13125);
DISPLAY INVISIBLE (8600 13125);
FORCEPROP 1 LAST COMMENT_BODY TRUE
R 1
J 0
(8675 12900);
DISPLAY 0.872340 (8675 12900);
PAINT GREEN (8675 12900);
DISPLAY INVISIBLE (8675 12900);
FORCEADD DNS..2
(6775 10225);
PAINT RED (6775 10225);
FORCEPROP 1 LAST COMMENT_BODY TRUE
R 1
J 0
(6850 10000);
DISPLAY 0.872340 (6850 10000);
PAINT GREEN (6850 10000);
DISPLAY INVISIBLE (6850 10000);
FORCEPROP 2 LAST CDS_LIB mstr_misc
J 0
(6775 10225);
DISPLAY INVISIBLE (6775 10225);
WIRE 16 -1 (3800 9075)(3800 9050);
WIRE 16 -1 (3800 9975)(3800 9950);
WIRE 16 -1 (3375 11050)(3375 10950);
WIRE 16 -1 (5850 8575)(5850 8525);
WIRE 16 -1 (5850 9475)(5850 9425);
WIRE 16 -1 (5350 11725)(5350 11650);
WIRE 16 -1 (8025 9550)(8025 9500);
WIRE 16 -1 (4125 12700)(4125 12600);
WIRE 16 -1 (5800 13825)(5800 13750);
WIRE 16 -1 (9550 11225)(9550 11200);
WIRE 16 -1 (10025 11900)(10025 11850);
WIRE 16 -1 (9775 13300)(9775 13275);
WIRE 16 -1 (10025 13925)(10025 13875);
WIRE 16 -1 (5850 8200)(5850 8250);
WIRE 16 -1 (4775 8275)(4775 8525);
WIRE 16 -1 (3375 10050)(3375 9950);
WIRE 16 -1 (3550 11425)(3550 11325);
WIRE 16 -1 (4775 9200)(4775 9425);
WIRE 16 -1 (5850 9100)(5850 9150);
WIRE 16 -1 (5925 10075)(5925 9975);
WIRE 16 -1 (4125 10375)(4125 10325);
WIRE 16 -1 (4125 11700)(4125 11600);
WIRE 16 -1 (4875 12075)(4875 11975);
WIRE 16 -1 (5350 11100)(5350 11160);
WIRE 16 -1 (6775 9950)(6775 10000);
WIRE 16 -1 (6250 10700)(6250 10675);
WIRE 16 -1 (6250 10900)(6250 10700);
WIRE 16 -1 (6250 10700)(6375 10700);
WIRE 16 -1 (6150 12175)(6150 12075);
WIRE 16 -1 (7000 12050)(7000 12100);
WIRE 16 -1 (5800 13425)(5800 13300);
WIRE 16 -1 (6475 12800)(6475 12775);
WIRE 16 -1 (6475 12800)(6600 12800);
WIRE 16 -1 (6475 13000)(6475 12800);
WIRE 16 -1 (8250 10075)(8250 10150);
WIRE 16 -1 (8475 12175)(8475 12250);
WIRE 16 -1 (9100 10800)(9100 10775);
WIRE 16 -1 (9075 10800)(9100 10800);
WIRE 16 -1 (10025 11350)(10025 11475);
WIRE 16 -1 (9300 12900)(9300 12875);
WIRE 16 -1 (9275 12900)(9300 12900);
WIRE 16 -1 (10025 13425)(10025 13500);
WIRE 16 -1 (5800 13750)(5800 13625);
WIRE 16 -1 (5800 13750)(6150 13750);
WIRE 16 -1 (6150 13750)(6150 13375);
WIRE 16 -1 (6150 13750)(6475 13750);
WIRE 16 -1 (6475 13750)(6475 13625);
WIRE 16 -1 (7250 13750)(6475 13750);
WIRE 16 -1 (7250 13300)(7350 13300);
WIRE 16 -1 (7250 13750)(7250 13300);
WIRE 16 -1 (7250 13300)(7250 13250);
WIRE 16 -1 (7250 13250)(7350 13250);
WIRE 16 -1 (7250 13250)(7250 13200);
WIRE 16 -1 (7250 13200)(7350 13200);
WIRE 16 -1 (7250 13200)(7250 13150);
WIRE 16 -1 (7250 13150)(7350 13150);
WIRE 16 -1 (7250 13150)(7250 13100);
WIRE 16 -1 (7250 13100)(7350 13100);
WIRE 16 -1 (7250 13050)(7350 13050);
WIRE 16 -1 (7250 13100)(7250 13050);
WIRE 16 -1 (7250 13050)(7250 13000);
WIRE 16 -1 (7250 13000)(7350 13000);
WIRE 16 -1 (5650 12900)(6150 12900);
WIRE 16 -1 (6150 13175)(6150 12900);
WIRE 16 -1 (6150 12700)(6150 12650);
WIRE 16 -1 (6150 12700)(6150 12900);
WIRE 16 -1 (6150 12700)(7350 12700);
FORCEPROP 2 LAST SIG_NAME P3V3_OCP_UV_1
J 0
(6915 12710);
DISPLAY 0.574468 (6915 12710);
WIRE 16 -1 (6475 13325)(6475 13200);
WIRE 16 -1 (6475 13425)(6475 13325);
WIRE 16 -1 (6825 13325)(6475 13325);
WIRE 16 -1 (6825 13325)(6825 12900);
WIRE 16 -1 (6825 12900)(7350 12900);
FORCEPROP 2 LAST SIG_NAME P3V3_OCP_VCC_1
J 0
(6890 12910);
DISPLAY 0.574468 (6890 12910);
WIRE 16 -1 (6500 8725)(6650 8725);
WIRE 16 -1 (5500 9475)(5625 9475);
WIRE 16 -1 (6475 9025)(6675 9025);
WIRE 16 -1 (6500 8875)(6500 8725);
WIRE 16 -1 (6500 8875)(6650 8875);
FORCEPROP 0 LAST CDS_PHYS_NET_NAME HP_LVC3_OCP_V3_1_PRSNT2_N_R
J 0
(6540 8917);
PAINT MONO (6540 8917);
DISPLAY INVISIBLE (6540 8917);
WIRE 16 -1 (5625 8475)(5500 8475);
WIRE 16 -1 (6475 8875)(6500 8875);
WIRE 16 -1 (6475 8875)(6475 9025);
WIRE 16 -1 (5625 9375)(5500 9375);
WIRE 16 -1 (5625 9475)(5625 9375);
WIRE 16 -1 (5625 9375)(5625 8875);
WIRE 16 -1 (5625 8875)(6475 8875);
FORCEPROP 2 LAST SIG_NAME HP_LVC3_OCP_V3_1_PRSNT2_N_R
J 0
(5690 8885);
DISPLAY 0.510638 (5690 8885);
PAINT WHITE (5690 8885);
WIRE 16 -1 (5625 8575)(5500 8575);
WIRE 16 -1 (5625 8575)(5625 8475);
WIRE 16 -1 (5625 8575)(5625 8875);
WIRE 16 -1 (6850 8875)(8250 8875);
FORCEPROP 0 LAST CDS_PHYS_NET_NAME HP_LVC3_OCP_V3_1_PRSNT2_N
J 0
(8215 8917);
PAINT MONO (8215 8917);
DISPLAY INVISIBLE (8215 8917);
FORCEPROP 2 LAST SIG_NAME HP_LVC3_OCP_V3_1_PRSNT2_N
J 0
(7165 8885);
DISPLAY 0.510638 (7165 8885);
PAINT WHITE (7165 8885);
WIRE 16 -1 (8250 8875)(9050 8875);
WIRE 16 -1 (8250 9200)(8250 8875);
WIRE 16 -1 (8600 8725)(6850 8725);
FORCEPROP 2 LAST SIG_NAME HP_LVC3_OCP_V3_1_PRSNT2_PLD_N
J 0
(7215 8735);
DISPLAY 0.553191 (7215 8735);
PAINT WHITE (7215 8735);
WIRE 16 -1 (8600 9200)(8600 8725);
WIRE 16 -1 (9050 8725)(8600 8725);
FORCEPROP 0 LAST CDS_PHYS_NET_NAME HP_LVC3_OCP_V3_1_PRSNT2_PLD_N
J 0
(8940 8767);
PAINT MONO (8940 8767);
DISPLAY INVISIBLE (8940 8767);
WIRE 16 -1 (6225 10500)(7125 10500);
FORCEPROP 2 LAST SIG_NAME P12V_OCP_OV_1
J 0
(6690 10510);
DISPLAY 0.510638 (6690 10510);
WIRE 16 -1 (6225 10300)(6225 10500);
WIRE 16 -1 (5925 10300)(5925 10275);
WIRE 16 -1 (5925 10350)(5925 10300);
WIRE 16 -1 (5925 10300)(6225 10300);
WIRE 16 -1 (10025 13500)(10025 13575);
WIRE 16 -1 (9450 13500)(9450 13575);
WIRE 16 -1 (10025 13500)(9450 13500);
WIRE 16 -1 (8950 13500)(9450 13500);
WIRE 16 -1 (8950 13575)(8950 13500);
WIRE 16 -1 (10025 13775)(10025 13875);
WIRE 16 -1 (9450 13775)(9450 13875);
WIRE 16 -1 (10025 13875)(9450 13875);
WIRE 16 -1 (8950 13875)(8950 13825);
WIRE 16 -1 (8950 13875)(9450 13875);
WIRE 16 -1 (8670 13875)(8950 13875);
WIRE 16 -1 (8825 13300)(8825 13225);
WIRE 16 -1 (8670 13300)(8825 13300);
WIRE 16 -1 (8670 13875)(8670 13300);
WIRE 16 -1 (8575 13225)(8575 13300);
WIRE 16 -1 (8575 13300)(8670 13300);
WIRE 16 -1 (8150 13300)(8457 13300);
WIRE 16 -1 (8457 13300)(8575 13300);
WIRE 16 -1 (8150 13250)(8457 13250);
WIRE 16 -1 (8457 13250)(8457 13300);
WIRE 16 -1 (8150 13200)(8457 13200);
WIRE 16 -1 (8457 13200)(8457 13250);
WIRE 16 -1 (8150 13150)(8457 13150);
WIRE 16 -1 (8457 13150)(8457 13200);
WIRE 16 -1 (8457 13100)(8150 13100);
WIRE 16 -1 (8457 13100)(8457 13150);
WIRE 16 -1 (8150 13050)(8457 13050);
WIRE 16 -1 (8457 13050)(8457 13100);
WIRE 16 -1 (8457 13000)(8457 13050);
WIRE 16 -1 (8150 13000)(8457 13000);
WIRE 16 -1 (9575 13275)(9575 13175);
WIRE 16 -1 (9775 13275)(9575 13275);
WIRE 16 -1 (9950 13275)(9775 13275);
WIRE 16 -1 (9950 13275)(9950 13175);
WIRE 16 -1 (9950 12800)(10225 12800);
WIRE 16 -1 (9950 12975)(9950 12800);
WIRE 16 -1 (9325 12800)(9950 12800);
FORCEPROP 2 LAST SIG_NAME OCP_V3_1_P3V3_PWRGD
J 0
(9590 12810);
DISPLAY 0.574468 (9590 12810);
WIRE 16 -1 (9575 12700)(9575 12975);
WIRE 16 -1 (8150 12700)(9575 12700);
FORCEPROP 2 LAST SIG_NAME P3V3_OCP_FAULT_1
J 0
(8215 12710);
DISPLAY 0.574468 (8215 12710);
WIRE 16 -1 (8150 12800)(9125 12800);
FORCEPROP 2 LAST SIG_NAME P3V3_OCP_PWRGD_1
J 0
(8215 12810);
DISPLAY 0.574468 (8215 12810);
WIRE 16 -1 (8575 12900)(8150 12900);
FORCEPROP 2 LAST SIG_NAME P3V3_OCP_GATE_PU202_1
J 0
(8215 12910);
DISPLAY 0.574468 (8215 12910);
WIRE 16 -1 (8575 13025)(8575 12900);
WIRE 16 -1 (8825 12900)(8575 12900);
WIRE 16 -1 (8825 13025)(8825 12900);
WIRE 16 -1 (9075 12900)(8825 12900);
WIRE 16 -1 (8600 12550)(8600 12600);
FORCEPROP 2 LAST SIG_NAME P3V3_OCP_SENSE_1
J 0
(8215 12610);
DISPLAY 0.574468 (8215 12610);
WIRE 16 -1 (8150 12600)(8600 12600);
WIRE 16 -1 (8225 12300)(8150 12300);
WIRE 16 -1 (8150 12350)(8275 12350);
WIRE 16 -1 (8225 12250)(8225 12300);
WIRE 16 -1 (8150 12400)(8325 12400);
WIRE 16 -1 (8225 12250)(8275 12250);
WIRE 16 -1 (8275 12350)(8275 12250);
WIRE 16 -1 (8150 12500)(8375 12500);
WIRE 16 -1 (8275 12250)(8325 12250);
WIRE 16 -1 (8325 12400)(8325 12250);
WIRE 16 -1 (8375 12250)(8325 12250);
WIRE 16 -1 (8375 12500)(8375 12250);
WIRE 16 -1 (8375 12250)(8475 12250);
WIRE 16 -1 (8475 12250)(8600 12250);
WIRE 16 -1 (8600 12350)(8600 12250);
WIRE 16 -1 (9375 10375)(10475 10375);
FORCEPROP 2 LAST SIG_NAME P12V_OCP_SFF_ISENSE_MAM_TIC
J 0
(9615 10385);
DISPLAY 0.510638 (9615 10385);
WIRE 16 -1 (9375 10500)(10475 10500);
FORCEPROP 2 LAST SIG_NAME P12V_OCP_SFF_ISENSE_MAM_MAM
J 0
(9615 10510);
DISPLAY 0.510638 (9615 10510);
WIRE 16 -1 (10025 11750)(10025 11850);
WIRE 16 -1 (9625 11850)(9625 11750);
WIRE 16 -1 (10025 11850)(9625 11850);
WIRE 16 -1 (9200 11750)(9200 11850);
WIRE 16 -1 (9625 11850)(9200 11850);
WIRE 16 -1 (8725 11850)(8725 11800);
WIRE 16 -1 (9200 11850)(8725 11850);
WIRE 16 -1 (8445 11850)(8725 11850);
WIRE 16 -1 (8625 11200)(8625 11125);
WIRE 16 -1 (8445 11200)(8625 11200);
WIRE 16 -1 (8445 11850)(8445 11200);
WIRE 16 -1 (8300 11125)(8300 11200);
WIRE 16 -1 (8300 11200)(8445 11200);
WIRE 16 -1 (7925 11200)(8232 11200);
WIRE 16 -1 (8232 11200)(8300 11200);
WIRE 16 -1 (7925 11150)(8232 11150);
WIRE 16 -1 (8232 11150)(8232 11200);
WIRE 16 -1 (7925 11100)(8232 11100);
WIRE 16 -1 (8232 11100)(8232 11150);
WIRE 16 -1 (7925 11050)(8232 11050);
WIRE 16 -1 (8232 11050)(8232 11100);
WIRE 16 -1 (8232 11000)(7925 11000);
WIRE 16 -1 (8232 11000)(8232 11050);
WIRE 16 -1 (7925 10950)(8232 10950);
WIRE 16 -1 (8232 10950)(8232 11000);
WIRE 16 -1 (8232 10900)(8232 10950);
WIRE 16 -1 (7925 10900)(8232 10900);
WIRE 16 -1 (10025 11475)(10025 11550);
WIRE 16 -1 (9625 11475)(9625 11550);
WIRE 16 -1 (10025 11475)(9625 11475);
WIRE 16 -1 (9200 11475)(9200 11550);
WIRE 16 -1 (9625 11475)(9200 11475);
WIRE 16 -1 (8725 11475)(9200 11475);
WIRE 16 -1 (8725 11550)(8725 11475);
WIRE 16 -1 (9375 11200)(9375 11075);
WIRE 16 -1 (9550 11200)(9375 11200);
WIRE 16 -1 (9800 11200)(9550 11200);
WIRE 16 -1 (9800 11200)(9800 11075);
WIRE 16 -1 (9800 10700)(10225 10700);
WIRE 16 -1 (9800 10875)(9800 10700);
FORCEPROP 2 LAST SIG_NAME HP_LVC3_OCP_V3_1_P12V_PWRGD
J 0
(9515 10710);
DISPLAY 0.510638 (9515 10710);
WIRE 16 -1 (9125 10700)(9800 10700);
WIRE 16 2175 (8875 10275)(9600 10275);
WIRE 16 2175 (9600 10575)(9600 10275);
WIRE 16 2175 (8875 10575)(8875 10275);
WIRE 16 2175 (8875 10575)(9600 10575);
WIRE 16 -1 (8825 10375)(9175 10375);
WIRE 16 -1 (8825 10500)(8825 10375);
WIRE 16 -1 (9175 10500)(8825 10500);
WIRE 16 -1 (8375 10400)(8375 10500);
FORCEPROP 2 LAST SIG_NAME P12V_OCP_SENSE_1
J 0
(7990 10510);
DISPLAY 0.510638 (7990 10510);
WIRE 16 -1 (8375 10500)(8825 10500);
WIRE 16 -1 (7925 10500)(8375 10500);
WIRE 16 -1 (8300 10800)(7925 10800);
FORCEPROP 2 LAST SIG_NAME P12V_OCP_GATE_1
J 0
(7990 10810);
DISPLAY 0.510638 (7990 10810);
WIRE 16 -1 (8300 10925)(8300 10800);
WIRE 16 -1 (8625 10800)(8300 10800);
WIRE 16 -1 (8625 10925)(8625 10800);
WIRE 16 -1 (8875 10800)(8625 10800);
WIRE 16 -1 (8025 9500)(8025 9400);
WIRE 16 -1 (8250 9500)(8025 9500);
WIRE 16 -1 (8250 9400)(8250 9500);
WIRE 16 -1 (8250 9500)(8600 9500);
WIRE 16 -1 (8600 9500)(8600 9400);
WIRE 16 -1 (8375 10200)(8375 10150);
WIRE 16 -1 (8250 10150)(8375 10150);
WIRE 16 -1 (7925 10400)(8150 10400);
WIRE 16 -1 (7925 10300)(8100 10300);
WIRE 16 -1 (8150 10400)(8150 10150);
WIRE 16 -1 (8150 10150)(8250 10150);
WIRE 16 -1 (7925 10250)(8050 10250);
WIRE 16 -1 (8150 10150)(8100 10150);
WIRE 16 -1 (8100 10300)(8100 10150);
WIRE 16 -1 (8050 10150)(8100 10150);
WIRE 16 -1 (8050 10250)(8050 10150);
WIRE 16 -1 (8000 10200)(7925 10200);
WIRE 16 -1 (8000 10150)(8050 10150);
WIRE 16 -1 (8000 10150)(8000 10200);
WIRE 16 -1 (7925 10700)(8925 10700);
FORCEPROP 2 LAST SIG_NAME P12V_OCP_PWRGD_1
J 0
(7990 10710);
DISPLAY 0.510638 (7990 10710);
WIRE 16 -1 (9375 10600)(9375 10875);
WIRE 16 -1 (7925 10600)(9375 10600);
FORCEPROP 2 LAST SIG_NAME P12V_OCP_FAULT_1
J 0
(7990 10610);
DISPLAY 0.510638 (7990 10610);
WIRE 16 -1 (6800 12800)(7350 12800);
FORCEPROP 2 LAST SIG_NAME P3V3_OCP_REG_1
J 0
(6890 12810);
DISPLAY 0.574468 (6890 12810);
WIRE 16 -1 (7000 12500)(7000 12400);
WIRE 16 -1 (7350 12500)(7000 12500);
FORCEPROP 2 LAST SIG_NAME P3V3_OCP_CB_1
J 0
(6915 12510);
DISPLAY 0.574468 (6915 12510);
WIRE 16 -1 (6450 12600)(7350 12600);
FORCEPROP 2 LAST SIG_NAME P3V3_OCP_OV_1
J 0
(6915 12610);
DISPLAY 0.574468 (6915 12610);
WIRE 16 -1 (6450 12400)(6450 12600);
WIRE 16 -1 (6150 12400)(6150 12375);
WIRE 16 -1 (6150 12450)(6150 12400);
WIRE 16 -1 (6150 12400)(6450 12400);
WIRE 16 -1 (5450 12900)(4875 12900);
FORCEPROP 2 LAST SIG_NAME P3V3_OCP_UV_1_R1
J 0
(4990 12910);
DISPLAY 0.574468 (4990 12910);
WIRE 16 -1 (4875 12475)(4875 12900);
WIRE 16 -1 (7000 12100)(7000 12200);
WIRE 16 -1 (7325 12100)(7000 12100);
WIRE 16 -1 (7325 12400)(7325 12100);
WIRE 16 -1 (7350 12400)(7325 12400);
WIRE 16 2175 (4600 12050)(5550 12050);
WIRE 16 2175 (5550 12550)(5550 12050);
WIRE 16 2175 (4600 12550)(4600 12050);
WIRE 16 2175 (4600 12550)(5550 12550);
WIRE 16 -1 (5200 11575)(5200 11650);
WIRE 16 -1 (5200 11650)(5350 11650);
WIRE 16 -1 (5575 11650)(5350 11650);
WIRE 16 -1 (5575 11650)(5575 11525);
WIRE 16 -1 (5925 11650)(5925 11225);
WIRE 16 -1 (5575 11650)(5925 11650);
WIRE 16 -1 (5925 11650)(6250 11650);
WIRE 16 -1 (6250 11650)(6250 11525);
WIRE 16 -1 (7025 11650)(6250 11650);
WIRE 16 -1 (7025 11200)(7125 11200);
WIRE 16 -1 (7025 11650)(7025 11200);
WIRE 16 -1 (7025 11200)(7025 11150);
WIRE 16 -1 (7025 11150)(7125 11150);
WIRE 16 -1 (7025 11150)(7025 11100);
WIRE 16 -1 (7025 11100)(7125 11100);
WIRE 16 -1 (7025 11100)(7025 11050);
WIRE 16 -1 (7025 11050)(7125 11050);
WIRE 16 -1 (7025 11000)(7125 11000);
WIRE 16 -1 (7025 11050)(7025 11000);
WIRE 16 -1 (7025 11000)(7025 10950);
WIRE 16 -1 (7025 10950)(7125 10950);
WIRE 16 -1 (7025 10950)(7025 10900);
WIRE 16 -1 (7025 10900)(7125 10900);
WIRE 16 -1 (6575 10700)(7125 10700);
FORCEPROP 2 LAST SIG_NAME P12V_OCP_REG_1
J 0
(6665 10710);
DISPLAY 0.510638 (6665 10710);
WIRE 16 -1 (6600 10800)(7125 10800);
FORCEPROP 2 LAST SIG_NAME P12V_OCP_VCC_1
J 0
(6665 10810);
DISPLAY 0.510638 (6665 10810);
WIRE 16 -1 (6600 11225)(6600 10800);
WIRE 16 -1 (6250 11225)(6250 11100);
WIRE 16 -1 (6600 11225)(6250 11225);
WIRE 16 -1 (6250 11325)(6250 11225);
WIRE 16 -1 (6775 10400)(6775 10300);
WIRE 16 -1 (7125 10400)(6775 10400);
FORCEPROP 2 LAST SIG_NAME P12V_OCP_CB_1
J 0
(6690 10410);
DISPLAY 0.510638 (6690 10410);
WIRE 16 -1 (6775 10000)(6775 10100);
WIRE 16 -1 (7100 10000)(6775 10000);
WIRE 16 -1 (7100 10300)(7100 10000);
WIRE 16 -1 (7125 10300)(7100 10300);
WIRE 16 -1 (8025 9200)(8025 9025);
WIRE 16 -1 (8025 9025)(9050 9025);
FORCEPROP 0 LAST CDS_PHYS_NET_NAME HP_LVC3_OCP_V3_1_ATTN_OUT_SW_N
J 0
(8940 9067);
PAINT MONO (8940 9067);
DISPLAY INVISIBLE (8940 9067);
WIRE 16 -1 (6875 9025)(8025 9025);
FORCEPROP 2 LAST SIG_NAME HP_LVC3_OCP_V3_1_ATTN_OUT_SW_N
J 0
(7190 9035);
DISPLAY 0.510638 (7190 9035);
PAINT WHITE (7190 9035);
WIRE 16 -1 (5500 10875)(5925 10875);
WIRE 16 -1 (5925 11025)(5925 10875);
WIRE 16 -1 (5925 10600)(5925 10550);
WIRE 16 -1 (5925 10600)(5925 10875);
WIRE 16 -1 (5925 10600)(7125 10600);
FORCEPROP 2 LAST SIG_NAME P12V_OCP_UV_1
J 0
(6690 10610);
DISPLAY 0.510638 (6690 10610);
WIRE 16 -1 (5575 11160)(5575 11325);
WIRE 16 -1 (5575 11160)(5350 11160);
WIRE 16 -1 (5200 11160)(5350 11160);
WIRE 16 -1 (5200 11275)(5200 11160);
WIRE 16 -1 (4125 12225)(4625 12225);
FORCEPROP 2 LAST SIG_NAME P3V3_OCP_1_EN_G
J 0
(4165 12235);
DISPLAY 0.595745 (4165 12235);
WIRE 16 -1 (4125 12400)(4125 12225);
WIRE 16 -1 (4125 12100)(4125 12225);
WIRE 16 -1 (5300 10875)(4125 10875);
FORCEPROP 2 LAST SIG_NAME P12V_OCP_UV_1_R
J 0
(4440 10885);
DISPLAY 0.510638 (4440 10885);
WIRE 16 -1 (4125 10775)(4125 10875);
WIRE 16 -1 (5850 9425)(5500 9425);
WIRE 16 -1 (5850 9350)(5850 9425);
WIRE 16 -1 (5850 8525)(5500 8525);
WIRE 16 -1 (5850 8450)(5850 8525);
WIRE 16 -1 (4775 9425)(4850 9425);
WIRE 16 -1 (4775 8525)(4850 8525);
WIRE 16 -1 (4025 8475)(3675 8475);
WIRE 16 -1 (4025 8725)(4025 8475);
WIRE 16 -1 (4850 8475)(4025 8475);
FORCEPROP 0 LAST CDS_PHYS_NET_NAME OCP_SFF_PRSNT3_R_N
J 0
(4740 8517);
PAINT MONO (4740 8517);
DISPLAY INVISIBLE (4740 8517);
FORCEPROP 2 LAST SIG_NAME OCP_SFF_PRSNT3_R_N
J 0
(4240 8485);
DISPLAY 0.510638 (4240 8485);
PAINT WHITE (4240 8485);
WIRE 16 2175 (3625 8675)(4300 8675);
WIRE 16 2175 (4300 9275)(4300 8675);
WIRE 16 2175 (3625 9275)(3625 8675);
WIRE 16 2175 (3625 9275)(4300 9275);
WIRE 16 -1 (4025 8925)(4025 9050);
WIRE 16 -1 (4025 9050)(3800 9050);
WIRE 16 -1 (3800 8925)(3800 9050);
WIRE 16 -1 (4025 9375)(3675 9375);
WIRE 16 -1 (4025 9625)(4025 9375);
WIRE 16 -1 (4850 9375)(4025 9375);
FORCEPROP 0 LAST CDS_PHYS_NET_NAME OCP_SFF_PRSNT1_R_N
J 0
(4740 9417);
PAINT MONO (4740 9417);
DISPLAY INVISIBLE (4740 9417);
FORCEPROP 2 LAST SIG_NAME OCP_SFF_PRSNT1_R_N
J 0
(4240 9385);
DISPLAY 0.510638 (4240 9385);
PAINT WHITE (4240 9385);
WIRE 16 -1 (3800 9825)(3800 9950);
WIRE 16 -1 (4025 9950)(3800 9950);
WIRE 16 -1 (4025 9825)(4025 9950);
WIRE 16 2175 (3575 9550)(4250 9550);
WIRE 16 2175 (4250 10150)(4250 9550);
WIRE 16 2175 (3575 10150)(3575 9550);
WIRE 16 2175 (3575 10150)(4250 10150);
WIRE 16 2175 (1625 13500)(3328 13500);
WIRE 16 2175 (3328 14400)(3328 13500);
WIRE 16 2175 (1625 14400)(1625 13500);
WIRE 16 2175 (1625 14400)(3328 14400);
WIRE 16 -1 (3550 11625)(3550 11850);
WIRE 16 -1 (3550 11850)(3875 11850);
WIRE 16 -1 (3275 11850)(3550 11850);
FORCEPROP 2 LAST SIG_NAME P3V3_OCP_EN_1_R
J 0
(3465 11860);
DISPLAY 0.595745 (3465 11860);
WIRE 16 -1 (3375 10750)(3375 10525);
WIRE 16 -1 (3375 10525)(3875 10525);
FORCEPROP 2 LAST SIG_NAME P12V_OCP_1_EN_G
J 0
(3415 10535);
DISPLAY 0.510638 (3415 10535);
WIRE 16 -1 (3375 10450)(3375 10525);
WIRE 16 -1 (2075 11850)(2125 11850);
FORCEPROP 2 LAST SIG_NAME HP_LVC3_OCP_V3_1_EN
J 0
(2090 11860);
DISPLAY 0.638298 (2090 11860);
WIRE 16 -1 (2125 11850)(3075 11850);
WIRE 16 -1 (2125 11850)(2125 10200);
WIRE 16 -1 (2325 10200)(2125 10200);
WIRE 16 -1 (3800 9475)(3675 9475);
WIRE 16 -1 (3800 9625)(3800 9475);
WIRE 16 -1 (4850 9475)(3800 9475);
FORCEPROP 0 LAST CDS_PHYS_NET_NAME OCP_SFF_PRSNT0_R_N
J 0
(4740 9517);
PAINT MONO (4740 9517);
DISPLAY INVISIBLE (4740 9517);
FORCEPROP 2 LAST SIG_NAME OCP_SFF_PRSNT0_R_N
J 0
(4240 9485);
DISPLAY 0.510638 (4240 9485);
PAINT WHITE (4240 9485);
WIRE 16 -1 (3800 8575)(3675 8575);
WIRE 16 -1 (3800 8725)(3800 8575);
WIRE 16 -1 (4850 8575)(3800 8575);
FORCEPROP 0 LAST CDS_PHYS_NET_NAME OCP_SFF_PRSNT2_R_N
J 0
(4740 8617);
PAINT MONO (4740 8617);
DISPLAY INVISIBLE (4740 8617);
FORCEPROP 2 LAST SIG_NAME OCP_SFF_PRSNT2_R_N
J 0
(4240 8585);
DISPLAY 0.510638 (4240 8585);
PAINT WHITE (4240 8585);
WIRE 16 -1 (2525 10200)(3125 10200);
FORCEPROP 2 LAST SIG_NAME P12V_OCP_EN_1_R
J 0
(2715 10210);
DISPLAY 0.510638 (2715 10210);
DOT 1 (7250 13150);
DOT 1 (3800 8575);
DOT 1 (3800 9050);
DOT 1 (3800 9475);
DOT 1 (3800 9950);
DOT 1 (2125 11850);
DOT 1 (3375 10525);
DOT 1 (3550 11850);
DOT 1 (4025 8475);
DOT 1 (4025 9375);
DOT 1 (5625 8575);
DOT 1 (5850 8525);
DOT 1 (5625 8875);
DOT 1 (5625 9375);
DOT 1 (5850 9425);
DOT 1 (4125 12225);
DOT 1 (5350 11160);
DOT 1 (5925 10300);
DOT 1 (5925 10600);
DOT 1 (5925 10875);
DOT 1 (5350 11650);
DOT 1 (5575 11650);
DOT 1 (5925 11650);
DOT 1 (6475 8875);
DOT 1 (6500 8875);
DOT 1 (6775 10000);
DOT 1 (8025 9025);
DOT 1 (8025 9500);
DOT 1 (6250 10700);
DOT 1 (6250 11225);
DOT 1 (6250 11650);
DOT 1 (7000 12100);
DOT 1 (7025 11000);
DOT 1 (7025 10950);
DOT 1 (7025 11100);
DOT 1 (7025 11050);
DOT 1 (7025 11150);
DOT 1 (7025 11200);
DOT 1 (5800 13750);
DOT 1 (6150 12400);
DOT 1 (6150 12700);
DOT 1 (6475 12800);
DOT 1 (6150 12900);
DOT 1 (6475 13325);
DOT 1 (6150 13750);
DOT 1 (6475 13750);
DOT 1 (7250 13050);
DOT 1 (7250 13100);
DOT 1 (7250 13200);
DOT 1 (7250 13300);
DOT 1 (7250 13250);
DOT 1 (8050 10150);
DOT 1 (8250 8875);
DOT 1 (8600 8725);
DOT 1 (8250 9500);
DOT 1 (8150 10150);
DOT 1 (8100 10150);
DOT 1 (8250 10150);
DOT 1 (8375 10500);
DOT 1 (8232 10950);
DOT 1 (8232 11000);
DOT 1 (8232 11100);
DOT 1 (8232 11050);
DOT 1 (8232 11150);
DOT 1 (8232 11200);
DOT 1 (8300 10800);
DOT 1 (8300 11200);
DOT 1 (8445 11200);
DOT 1 (8825 10500);
DOT 1 (8625 10800);
DOT 1 (8275 12250);
DOT 1 (8325 12250);
DOT 1 (8375 12250);
DOT 1 (8475 12250);
DOT 1 (8725 11850);
DOT 1 (9550 11200);
DOT 1 (9800 10700);
DOT 1 (9200 11475);
DOT 1 (9200 11850);
DOT 1 (9625 11475);
DOT 1 (10025 11475);
DOT 1 (9625 11850);
DOT 1 (10025 11850);
DOT 1 (8457 13050);
DOT 1 (8457 13100);
DOT 1 (8457 13150);
DOT 1 (8457 13200);
DOT 1 (8457 13250);
DOT 1 (8457 13300);
DOT 1 (8575 12900);
DOT 1 (8575 13300);
DOT 1 (8670 13300);
DOT 1 (8825 12900);
DOT 1 (8950 13875);
DOT 1 (9950 12800);
DOT 1 (9775 13275);
DOT 1 (9450 13500);
DOT 1 (9450 13875);
DOT 1 (10025 13500);
DOT 1 (10025 13875);
FORCENOTE
20211130 CHANGE TO 1K OHM
(2350 8875) 0;
DISPLAY LEFT (2350 8875);
DISPLAY 1.021277 (2350 8875);
PAINT PINK (2350 8875);
FORCENOTE
20211130 CHANGE TO 1K OHM
(2350 9725) 0;
DISPLAY LEFT (2350 9725);
DISPLAY 1.021277 (2350 9725);
PAINT PINK (2350 9725);
FORCENOTE
DESIGN SPECIFICATION
(1675 14325) 0;
DISPLAY LEFT (1675 14325);
DISPLAY 1.170213 (1675 14325);
FORCENOTE
OCP=IMAX*1.3=1.43A
(1675 14075) 0;
DISPLAY LEFT (1675 14075);
DISPLAY 0.936170 (1675 14075);
FORCENOTE
OCP=IMAX*1.3=8.58A
(1675 13675) 0;
DISPLAY LEFT (1675 13675);
DISPLAY 1.021277 (1675 13675);
FORCENOTE
P12V_OCP_V3
(1675 13825) 0;
DISPLAY LEFT (1675 13825);
DISPLAY 1.021277 (1675 13825);
FORCENOTE
IMAX=6.6A
(1675 13750) 0;
DISPLAY LEFT (1675 13750);
DISPLAY 1.021277 (1675 13750);
FORCENOTE
IMAX=1.1A
(1675 14150) 0;
DISPLAY LEFT (1675 14150);
DISPLAY 0.936170 (1675 14150);
FORCENOTE
P3V3_OCP_V3
(1675 14225) 0;
DISPLAY LEFT (1675 14225);
DISPLAY 0.936170 (1675 14225);
FORCENOTE
UVP: 10.17V
(5350 10550) 0;
DISPLAY LEFT (5350 10550);
DISPLAY 0.808511 (5350 10550);
PAINT WHITE (5350 10550);
FORCENOTE
OVP: 14.91V
(5350 10475) 0;
DISPLAY LEFT (5350 10475);
DISPLAY 0.808511 (5350 10475);
PAINT WHITE (5350 10475);
FORCENOTE
20220802 CHANGE TO Q124
(4925 11975) 0;
DISPLAY LEFT (4925 11975);
DISPLAY 1.063830 (4925 11975);
PAINT WHITE (4925 11975);
FORCENOTE
VIMON(MAX)= 1.594V @ IOUT=1.6A
(7175 11925) 0;
DISPLAY LEFT (7175 11925);
DISPLAY 0.510638 (7175 11925);
PAINT WHITE (7175 11925);
FORCENOTE
OVP: 3.89V
(5625 12525) 0;
DISPLAY LEFT (5625 12525);
DISPLAY 1.021277 (5625 12525);
PAINT WHITE (5625 12525);
FORCENOTE
UVP: 2.63V
(5625 12600) 0;
DISPLAY LEFT (5625 12600);
DISPLAY 1.021277 (5625 12600);
PAINT WHITE (5625 12600);
FORCENOTE
20211108 MODIFY FOR GT
(3975 14200) 0;
DISPLAY LEFT (3975 14200);
DISPLAY 2.510638 (3975 14200);
PAINT PINK (3975 14200);
FORCENOTE
VIMON(MAX)= 1.594V @ IOUT=1.6A
(7175 11975) 0;
DISPLAY LEFT (7175 11975);
DISPLAY 1.021277 (7175 11975);
PAINT WHITE (7175 11975);
FORCENOTE
VIMON(MAX)= 1.679V @ IOUT=9.03A
(7100 9800) 0;
DISPLAY LEFT (7100 9800);
DISPLAY 0.808511 (7100 9800);
PAINT WHITE (7100 9800);
FORCENOTE
START UP TIME:8.21MS
(9675 10575) 0;
DISPLAY LEFT (9675 10575);
DISPLAY 0.638298 (9675 10575);
PAINT WHITE (9675 10575);
FORCENOTE
START UP TIME:3.94MS
(9050 12575) 0;
DISPLAY LEFT (9050 12575);
DISPLAY 1.021277 (9050 12575);
PAINT WHITE (9050 12575);
QUIT
